G04 ================== begin FILE IDENTIFICATION RECORD ==================*
G04 Layout Name:  D:/<user>/Wistron_project/16342-2/gbr/16342-2.brd*
G04 Film Name:    L8*
G04 File Format:  Gerber RS274X*
G04 File Origin:  Cadence Allegro 16.5-S056*
G04 Origin Date:  Mon Aug 07 11:24:57 2017*
G04 *
G04 Layer:  VIA CLASS/BOTTOM*
G04 Layer:  PIN/BOTTOM*
G04 Layer:  ETCH/BOTTOM*
G04 Layer:  DRAWING FORMAT/LAYER_PCB_STORY*
G04 Layer:  DRAWING FORMAT/LAYER_L8*
G04 *
G04 Offset:    (0.00 0.00)*
G04 Mirror:    No*
G04 Mode:      Positive*
G04 Rotation:  0*
G04 FullContactRelief:  No*
G04 UndefLineWidth:     6.00*
G04 ================== end FILE IDENTIFICATION RECORD ====================*
%FSLAX35Y35*MOIN*%
%IR0*IPPOS*OFA0.00000B0.00000*MIA0B0*SFA1.00000B1.00000*%
%AMMACRO42*
4,1,40,.011,.007,
.011,-.007,
.010939,-.007695,
.010759,-.008368,
.010464,-.009,
.010064,-.009571,
.009571,-.010064,
.009,-.010464,
.008368,-.010759,
.007695,-.010939,
.007,-.011,
-.007,-.011,
-.007695,-.010939,
-.008368,-.010759,
-.009,-.010464,
-.009571,-.010064,
-.010064,-.009571,
-.010464,-.009,
-.010759,-.008368,
-.010939,-.007695,
-.011,-.007,
-.011,.007,
-.010939,.007695,
-.010759,.008368,
-.010464,.009,
-.010064,.009571,
-.009571,.010064,
-.009,.010464,
-.008368,.010759,
-.007695,.010939,
-.007,.011,
.007,.011,
.007695,.010939,
.008368,.010759,
.009,.010464,
.009571,.010064,
.010064,.009571,
.010464,.009,
.010759,.008368,
.010939,.007695,
.011,.007,
0.0*
%
%ADD42MACRO42*%
%AMMACRO27*
4,1,40,-.017,-.013,
-.017,.013,
-.016939,.013695,
-.016759,.014368,
-.016464,.015,
-.016064,.015571,
-.015571,.016064,
-.015,.016464,
-.014368,.016759,
-.013695,.016939,
-.013,.017,
.013,.017,
.013695,.016939,
.014368,.016759,
.015,.016464,
.015571,.016064,
.016064,.015571,
.016464,.015,
.016759,.014368,
.016939,.013695,
.017,.013,
.017,-.013,
.016939,-.013695,
.016759,-.014368,
.016464,-.015,
.016064,-.015571,
.015571,-.016064,
.015,-.016464,
.014368,-.016759,
.013695,-.016939,
.013,-.017,
-.013,-.017,
-.013695,-.016939,
-.014368,-.016759,
-.015,-.016464,
-.015571,-.016064,
-.016064,-.015571,
-.016464,-.015,
-.016759,-.014368,
-.016939,-.013695,
-.017,-.013,
0.0*
%
%ADD27MACRO27*%
%AMMACRO25*
4,1,40,.013,-.017,
-.013,-.017,
-.013695,-.016939,
-.014368,-.016759,
-.015,-.016464,
-.015571,-.016064,
-.016064,-.015571,
-.016464,-.015,
-.016759,-.014368,
-.016939,-.013695,
-.017,-.013,
-.017,.013,
-.016939,.013695,
-.016759,.014368,
-.016464,.015,
-.016064,.015571,
-.015571,.016064,
-.015,.016464,
-.014368,.016759,
-.013695,.016939,
-.013,.017,
.013,.017,
.013695,.016939,
.014368,.016759,
.015,.016464,
.015571,.016064,
.016064,.015571,
.016464,.015,
.016759,.014368,
.016939,.013695,
.017,.013,
.017,-.013,
.016939,-.013695,
.016759,-.014368,
.016464,-.015,
.016064,-.015571,
.015571,-.016064,
.015,-.016464,
.014368,-.016759,
.013695,-.016939,
.013,-.017,
0.0*
%
%ADD25MACRO25*%
%ADD51O,.06X.111*%
%ADD14C,.01*%
%ADD12C,.02*%
%ADD56C,.03*%
%ADD28C,.022*%
%ADD13C,.04*%
%ADD63C,.05*%
%ADD44C,.032*%
%ADD50C,.042*%
%ADD22C,.024*%
%ADD57C,.026*%
%ADD47C,.018*%
%ADD11C,.028*%
%ADD10C,.056*%
%AMMACRO54*
4,1,40,.008,.014,
-.008,.014,
-.008695,.013939,
-.009368,.013759,
-.01,.013464,
-.010571,.013064,
-.011064,.012571,
-.011464,.012,
-.011759,.011368,
-.011939,.010695,
-.012,.01,
-.012,-.01,
-.011939,-.010695,
-.011759,-.011368,
-.011464,-.012,
-.011064,-.012571,
-.010571,-.013064,
-.01,-.013464,
-.009368,-.013759,
-.008695,-.013939,
-.008,-.014,
.008,-.014,
.008695,-.013939,
.009368,-.013759,
.01,-.013464,
.010571,-.013064,
.011064,-.012571,
.011464,-.012,
.011759,-.011368,
.011939,-.010695,
.012,-.01,
.012,.01,
.011939,.010695,
.011759,.011368,
.011464,.012,
.011064,.012571,
.010571,.013064,
.01,.013464,
.009368,.013759,
.008695,.013939,
.008,.014,
0.0*
%
%ADD54MACRO54*%
%AMMACRO61*
4,1,40,.007,-.0225,
.008389,-.022378,
.009736,-.022018,
.011,-.021428,
.012142,-.020628,
.013128,-.019642,
.013928,-.0185,
.014518,-.017236,
.014878,-.015889,
.015,-.0145,
.015,.0145,
.014878,.015889,
.014518,.017236,
.013928,.0185,
.013128,.019642,
.012142,.020628,
.011,.021428,
.009736,.022018,
.008389,.022378,
.007,.0225,
-.007,.0225,
-.008389,.022378,
-.009736,.022018,
-.011,.021428,
-.012142,.020628,
-.013128,.019642,
-.013928,.0185,
-.014518,.017236,
-.014878,.015889,
-.015,.0145,
-.015,-.0145,
-.014878,-.015889,
-.014518,-.017236,
-.013928,-.0185,
-.013128,-.019642,
-.012142,-.020628,
-.011,-.021428,
-.009736,-.022018,
-.008389,-.022378,
-.007,-.0225,
.007,-.0225,
0.0*
%
%ADD61MACRO61*%
%AMMACRO60*
4,1,40,.014,-.008,
.014,.008,
.013939,.008695,
.013759,.009368,
.013464,.01,
.013064,.010571,
.012571,.011064,
.012,.011464,
.011368,.011759,
.010695,.011939,
.01,.012,
-.01,.012,
-.010695,.011939,
-.011368,.011759,
-.012,.011464,
-.012571,.011064,
-.013064,.010571,
-.013464,.01,
-.013759,.009368,
-.013939,.008695,
-.014,.008,
-.014,-.008,
-.013939,-.008695,
-.013759,-.009368,
-.013464,-.01,
-.013064,-.010571,
-.012571,-.011064,
-.012,-.011464,
-.011368,-.011759,
-.010695,-.011939,
-.01,-.012,
.01,-.012,
.010695,-.011939,
.011368,-.011759,
.012,-.011464,
.012571,-.011064,
.013064,-.010571,
.013464,-.01,
.013759,-.009368,
.013939,-.008695,
.014,-.008,
0.0*
%
%ADD60MACRO60*%
%AMMACRO32*
4,1,40,.007,-.011,
-.007,-.011,
-.007695,-.010939,
-.008368,-.010759,
-.009,-.010464,
-.009571,-.010064,
-.010064,-.009571,
-.010464,-.009,
-.010759,-.008368,
-.010939,-.007695,
-.011,-.007,
-.011,.007,
-.010939,.007695,
-.010759,.008368,
-.010464,.009,
-.010064,.009571,
-.009571,.010064,
-.009,.010464,
-.008368,.010759,
-.007695,.010939,
-.007,.011,
.007,.011,
.007695,.010939,
.008368,.010759,
.009,.010464,
.009571,.010064,
.010064,.009571,
.010464,.009,
.010759,.008368,
.010939,.007695,
.011,.007,
.011,-.007,
.010939,-.007695,
.010759,-.008368,
.010464,-.009,
.010064,-.009571,
.009571,-.010064,
.009,-.010464,
.008368,-.010759,
.007695,-.010939,
.007,-.011,
0.0*
%
%ADD32MACRO32*%
%AMMACRO18*
4,1,40,-.011,-.007,
-.011,.007,
-.010939,.007695,
-.010759,.008368,
-.010464,.009,
-.010064,.009571,
-.009571,.010064,
-.009,.010464,
-.008368,.010759,
-.007695,.010939,
-.007,.011,
.007,.011,
.007695,.010939,
.008368,.010759,
.009,.010464,
.009571,.010064,
.010064,.009571,
.010464,.009,
.010759,.008368,
.010939,.007695,
.011,.007,
.011,-.007,
.010939,-.007695,
.010759,-.008368,
.010464,-.009,
.010064,-.009571,
.009571,-.010064,
.009,-.010464,
.008368,-.010759,
.007695,-.010939,
.007,-.011,
-.007,-.011,
-.007695,-.010939,
-.008368,-.010759,
-.009,-.010464,
-.009571,-.010064,
-.010064,-.009571,
-.010464,-.009,
-.010759,-.008368,
-.010939,-.007695,
-.011,-.007,
0.0*
%
%ADD18MACRO18*%
%AMMACRO38*
4,1,40,-.012,-.008,
-.012,.008,
-.011939,.008695,
-.011759,.009368,
-.011464,.01,
-.011064,.010571,
-.010571,.011064,
-.01,.011464,
-.009368,.011759,
-.008695,.011939,
-.008,.012,
.008,.012,
.008695,.011939,
.009368,.011759,
.01,.011464,
.010571,.011064,
.011064,.010571,
.011464,.01,
.011759,.009368,
.011939,.008695,
.012,.008,
.012,-.008,
.011939,-.008695,
.011759,-.009368,
.011464,-.01,
.011064,-.010571,
.010571,-.011064,
.01,-.011464,
.009368,-.011759,
.008695,-.011939,
.008,-.012,
-.008,-.012,
-.008695,-.011939,
-.009368,-.011759,
-.01,-.011464,
-.010571,-.011064,
-.011064,-.010571,
-.011464,-.01,
-.011759,-.009368,
-.011939,-.008695,
-.012,-.008,
0.0*
%
%ADD38MACRO38*%
%AMMACRO40*
4,1,40,-.008,.012,
.008,.012,
.008695,.011939,
.009368,.011759,
.01,.011464,
.010571,.011064,
.011064,.010571,
.011464,.01,
.011759,.009368,
.011939,.008695,
.012,.008,
.012,-.008,
.011939,-.008695,
.011759,-.009368,
.011464,-.01,
.011064,-.010571,
.010571,-.011064,
.01,-.011464,
.009368,-.011759,
.008695,-.011939,
.008,-.012,
-.008,-.012,
-.008695,-.011939,
-.009368,-.011759,
-.01,-.011464,
-.010571,-.011064,
-.011064,-.010571,
-.011464,-.01,
-.011759,-.009368,
-.011939,-.008695,
-.012,-.008,
-.012,.008,
-.011939,.008695,
-.011759,.009368,
-.011464,.01,
-.011064,.010571,
-.010571,.011064,
-.01,.011464,
-.009368,.011759,
-.008695,.011939,
-.008,.012,
0.0*
%
%ADD40MACRO40*%
%AMMACRO65*
4,1,6,.0135,.025,
-.0065,.005,
-.0135,.005,
-.0135,-.005,
-.0065,-.005,
.0135,-.025,
.0135,.025,
0.0*
%
%ADD65MACRO65*%
%AMMACRO35*
4,1,40,-.013,.017,
.013,.017,
.013695,.016939,
.014368,.016759,
.015,.016464,
.015571,.016064,
.016064,.015571,
.016464,.015,
.016759,.014368,
.016939,.013695,
.017,.013,
.017,-.013,
.016939,-.013695,
.016759,-.014368,
.016464,-.015,
.016064,-.015571,
.015571,-.016064,
.015,-.016464,
.014368,-.016759,
.013695,-.016939,
.013,-.017,
-.013,-.017,
-.013695,-.016939,
-.014368,-.016759,
-.015,-.016464,
-.015571,-.016064,
-.016064,-.015571,
-.016464,-.015,
-.016759,-.014368,
-.016939,-.013695,
-.017,-.013,
-.017,.013,
-.016939,.013695,
-.016759,.014368,
-.016464,.015,
-.016064,.015571,
-.015571,.016064,
-.015,.016464,
-.014368,.016759,
-.013695,.016939,
-.013,.017,
0.0*
%
%ADD35MACRO35*%
%AMMACRO45*
4,1,40,.017,.013,
.017,-.013,
.016939,-.013695,
.016759,-.014368,
.016464,-.015,
.016064,-.015571,
.015571,-.016064,
.015,-.016464,
.014368,-.016759,
.013695,-.016939,
.013,-.017,
-.013,-.017,
-.013695,-.016939,
-.014368,-.016759,
-.015,-.016464,
-.015571,-.016064,
-.016064,-.015571,
-.016464,-.015,
-.016759,-.014368,
-.016939,-.013695,
-.017,-.013,
-.017,.013,
-.016939,.013695,
-.016759,.014368,
-.016464,.015,
-.016064,.015571,
-.015571,.016064,
-.015,.016464,
-.014368,.016759,
-.013695,.016939,
-.013,.017,
.013,.017,
.013695,.016939,
.014368,.016759,
.015,.016464,
.015571,.016064,
.016064,.015571,
.016464,.015,
.016759,.014368,
.016939,.013695,
.017,.013,
0.0*
%
%ADD45MACRO45*%
%AMMACRO33*
4,1,40,.007,-.011,
-.007,-.011,
-.007695,-.010939,
-.008368,-.010759,
-.009,-.010464,
-.009571,-.010064,
-.010064,-.009571,
-.010464,-.009,
-.010759,-.008368,
-.010939,-.007695,
-.011,-.007,
-.011,.007,
-.010939,.007695,
-.010759,.008368,
-.010464,.009,
-.010064,.009571,
-.009571,.010064,
-.009,.010464,
-.008368,.010759,
-.007695,.010939,
-.007,.011,
.007,.011,
.007695,.010939,
.008368,.010759,
.009,.010464,
.009571,.010064,
.010064,.009571,
.010464,.009,
.010759,.008368,
.010939,.007695,
.011,.007,
.011,-.007,
.010939,-.007695,
.010759,-.008368,
.010464,-.009,
.010064,-.009571,
.009571,-.010064,
.009,-.010464,
.008368,-.010759,
.007695,-.010939,
.007,-.011,
0.0*
%
%ADD33MACRO33*%
%AMMACRO19*
4,1,40,-.011,-.007,
-.011,.007,
-.010939,.007695,
-.010759,.008368,
-.010464,.009,
-.010064,.009571,
-.009571,.010064,
-.009,.010464,
-.008368,.010759,
-.007695,.010939,
-.007,.011,
.007,.011,
.007695,.010939,
.008368,.010759,
.009,.010464,
.009571,.010064,
.010064,.009571,
.010464,.009,
.010759,.008368,
.010939,.007695,
.011,.007,
.011,-.007,
.010939,-.007695,
.010759,-.008368,
.010464,-.009,
.010064,-.009571,
.009571,-.010064,
.009,-.010464,
.008368,-.010759,
.007695,-.010939,
.007,-.011,
-.007,-.011,
-.007695,-.010939,
-.008368,-.010759,
-.009,-.010464,
-.009571,-.010064,
-.010064,-.009571,
-.010464,-.009,
-.010759,-.008368,
-.010939,-.007695,
-.011,-.007,
0.0*
%
%ADD19MACRO19*%
%AMMACRO37*
4,1,40,-.012,-.008,
-.012,.008,
-.011939,.008695,
-.011759,.009368,
-.011464,.01,
-.011064,.010571,
-.010571,.011064,
-.01,.011464,
-.009368,.011759,
-.008695,.011939,
-.008,.012,
.008,.012,
.008695,.011939,
.009368,.011759,
.01,.011464,
.010571,.011064,
.011064,.010571,
.011464,.01,
.011759,.009368,
.011939,.008695,
.012,.008,
.012,-.008,
.011939,-.008695,
.011759,-.009368,
.011464,-.01,
.011064,-.010571,
.010571,-.011064,
.01,-.011464,
.009368,-.011759,
.008695,-.011939,
.008,-.012,
-.008,-.012,
-.008695,-.011939,
-.009368,-.011759,
-.01,-.011464,
-.010571,-.011064,
-.011064,-.010571,
-.011464,-.01,
-.011759,-.009368,
-.011939,-.008695,
-.012,-.008,
0.0*
%
%ADD37MACRO37*%
%AMMACRO39*
4,1,40,-.008,.012,
.008,.012,
.008695,.011939,
.009368,.011759,
.01,.011464,
.010571,.011064,
.011064,.010571,
.011464,.01,
.011759,.009368,
.011939,.008695,
.012,.008,
.012,-.008,
.011939,-.008695,
.011759,-.009368,
.011464,-.01,
.011064,-.010571,
.010571,-.011064,
.01,-.011464,
.009368,-.011759,
.008695,-.011939,
.008,-.012,
-.008,-.012,
-.008695,-.011939,
-.009368,-.011759,
-.01,-.011464,
-.010571,-.011064,
-.011064,-.010571,
-.011464,-.01,
-.011759,-.009368,
-.011939,-.008695,
-.012,-.008,
-.012,.008,
-.011939,.008695,
-.011759,.009368,
-.011464,.01,
-.011064,.010571,
-.010571,.011064,
-.01,.011464,
-.009368,.011759,
-.008695,.011939,
-.008,.012,
0.0*
%
%ADD39MACRO39*%
%AMMACRO36*
4,1,40,-.013,.017,
.013,.017,
.013695,.016939,
.014368,.016759,
.015,.016464,
.015571,.016064,
.016064,.015571,
.016464,.015,
.016759,.014368,
.016939,.013695,
.017,.013,
.017,-.013,
.016939,-.013695,
.016759,-.014368,
.016464,-.015,
.016064,-.015571,
.015571,-.016064,
.015,-.016464,
.014368,-.016759,
.013695,-.016939,
.013,-.017,
-.013,-.017,
-.013695,-.016939,
-.014368,-.016759,
-.015,-.016464,
-.015571,-.016064,
-.016064,-.015571,
-.016464,-.015,
-.016759,-.014368,
-.016939,-.013695,
-.017,-.013,
-.017,.013,
-.016939,.013695,
-.016759,.014368,
-.016464,.015,
-.016064,.015571,
-.015571,.016064,
-.015,.016464,
-.014368,.016759,
-.013695,.016939,
-.013,.017,
0.0*
%
%ADD36MACRO36*%
%AMMACRO46*
4,1,40,.017,.013,
.017,-.013,
.016939,-.013695,
.016759,-.014368,
.016464,-.015,
.016064,-.015571,
.015571,-.016064,
.015,-.016464,
.014368,-.016759,
.013695,-.016939,
.013,-.017,
-.013,-.017,
-.013695,-.016939,
-.014368,-.016759,
-.015,-.016464,
-.015571,-.016064,
-.016064,-.015571,
-.016464,-.015,
-.016759,-.014368,
-.016939,-.013695,
-.017,-.013,
-.017,.013,
-.016939,.013695,
-.016759,.014368,
-.016464,.015,
-.016064,.015571,
-.015571,.016064,
-.015,.016464,
-.014368,.016759,
-.013695,.016939,
-.013,.017,
.013,.017,
.013695,.016939,
.014368,.016759,
.015,.016464,
.015571,.016064,
.016064,.015571,
.016464,.015,
.016759,.014368,
.016939,.013695,
.017,.013,
0.0*
%
%ADD46MACRO46*%
%ADD43R,.06X.014*%
%ADD62R,.014X.06*%
%ADD55R,.05X.065*%
%ADD52O,.06X.084*%
%ADD34R,.048X.016*%
%ADD23R,.045X.055*%
%ADD49R,.016X.048*%
%ADD31R,.055X.045*%
%ADD48C,.256*%
%ADD15C,.375*%
%AMMACRO59*
4,1,40,-.014,.008,
-.014,-.008,
-.013939,-.008695,
-.013759,-.009368,
-.013464,-.01,
-.013064,-.010571,
-.012571,-.011064,
-.012,-.011464,
-.011368,-.011759,
-.010695,-.011939,
-.01,-.012,
.01,-.012,
.010695,-.011939,
.011368,-.011759,
.012,-.011464,
.012571,-.011064,
.013064,-.010571,
.013464,-.01,
.013759,-.009368,
.013939,-.008695,
.014,-.008,
.014,.008,
.013939,.008695,
.013759,.009368,
.013464,.01,
.013064,.010571,
.012571,.011064,
.012,.011464,
.011368,.011759,
.010695,.011939,
.01,.012,
-.01,.012,
-.010695,.011939,
-.011368,.011759,
-.012,.011464,
-.012571,.011064,
-.013064,.010571,
-.013464,.01,
-.013759,.009368,
-.013939,.008695,
-.014,.008,
0.0*
%
%ADD59MACRO59*%
%AMMACRO58*
4,1,40,-.0225,-.007,
-.022378,-.008389,
-.022018,-.009736,
-.021428,-.011,
-.020628,-.012142,
-.019642,-.013128,
-.0185,-.013928,
-.017236,-.014518,
-.015889,-.014878,
-.0145,-.015,
.0145,-.015,
.015889,-.014878,
.017236,-.014518,
.0185,-.013928,
.019642,-.013128,
.020628,-.012142,
.021428,-.011,
.022018,-.009736,
.022378,-.008389,
.0225,-.007,
.0225,.007,
.022378,.008389,
.022018,.009736,
.021428,.011,
.020628,.012142,
.019642,.013128,
.0185,.013928,
.017236,.014518,
.015889,.014878,
.0145,.015,
-.0145,.015,
-.015889,.014878,
-.017236,.014518,
-.0185,.013928,
-.019642,.013128,
-.020628,.012142,
-.021428,.011,
-.022018,.009736,
-.022378,.008389,
-.0225,.007,
-.0225,-.007,
0.0*
%
%ADD58MACRO58*%
%AMMACRO53*
4,1,40,-.007,.0225,
-.008389,.022378,
-.009736,.022018,
-.011,.021428,
-.012142,.020628,
-.013128,.019642,
-.013928,.0185,
-.014518,.017236,
-.014878,.015889,
-.015,.0145,
-.015,-.0145,
-.014878,-.015889,
-.014518,-.017236,
-.013928,-.0185,
-.013128,-.019642,
-.012142,-.020628,
-.011,-.021428,
-.009736,-.022018,
-.008389,-.022378,
-.007,-.0225,
.007,-.0225,
.008389,-.022378,
.009736,-.022018,
.011,-.021428,
.012142,-.020628,
.013128,-.019642,
.013928,-.0185,
.014518,-.017236,
.014878,-.015889,
.015,-.0145,
.015,.0145,
.014878,.015889,
.014518,.017236,
.013928,.0185,
.013128,.019642,
.012142,.020628,
.011,.021428,
.009736,.022018,
.008389,.022378,
.007,.0225,
-.007,.0225,
0.0*
%
%ADD53MACRO53*%
%AMMACRO30*
4,1,40,.012,.008,
.012,-.008,
.011939,-.008695,
.011759,-.009368,
.011464,-.01,
.011064,-.010571,
.010571,-.011064,
.01,-.011464,
.009368,-.011759,
.008695,-.011939,
.008,-.012,
-.008,-.012,
-.008695,-.011939,
-.009368,-.011759,
-.01,-.011464,
-.010571,-.011064,
-.011064,-.010571,
-.011464,-.01,
-.011759,-.009368,
-.011939,-.008695,
-.012,-.008,
-.012,.008,
-.011939,.008695,
-.011759,.009368,
-.011464,.01,
-.011064,.010571,
-.010571,.011064,
-.01,.011464,
-.009368,.011759,
-.008695,.011939,
-.008,.012,
.008,.012,
.008695,.011939,
.009368,.011759,
.01,.011464,
.010571,.011064,
.011064,.010571,
.011464,.01,
.011759,.009368,
.011939,.008695,
.012,.008,
0.0*
%
%ADD30MACRO30*%
%AMMACRO20*
4,1,40,-.007,.011,
.007,.011,
.007695,.010939,
.008368,.010759,
.009,.010464,
.009571,.010064,
.010064,.009571,
.010464,.009,
.010759,.008368,
.010939,.007695,
.011,.007,
.011,-.007,
.010939,-.007695,
.010759,-.008368,
.010464,-.009,
.010064,-.009571,
.009571,-.010064,
.009,-.010464,
.008368,-.010759,
.007695,-.010939,
.007,-.011,
-.007,-.011,
-.007695,-.010939,
-.008368,-.010759,
-.009,-.010464,
-.009571,-.010064,
-.010064,-.009571,
-.010464,-.009,
-.010759,-.008368,
-.010939,-.007695,
-.011,-.007,
-.011,.007,
-.010939,.007695,
-.010759,.008368,
-.010464,.009,
-.010064,.009571,
-.009571,.010064,
-.009,.010464,
-.008368,.010759,
-.007695,.010939,
-.007,.011,
0.0*
%
%ADD20MACRO20*%
%AMMACRO17*
4,1,40,.008,-.012,
-.008,-.012,
-.008695,-.011939,
-.009368,-.011759,
-.01,-.011464,
-.010571,-.011064,
-.011064,-.010571,
-.011464,-.01,
-.011759,-.009368,
-.011939,-.008695,
-.012,-.008,
-.012,.008,
-.011939,.008695,
-.011759,.009368,
-.011464,.01,
-.011064,.010571,
-.010571,.011064,
-.01,.011464,
-.009368,.011759,
-.008695,.011939,
-.008,.012,
.008,.012,
.008695,.011939,
.009368,.011759,
.01,.011464,
.010571,.011064,
.011064,.010571,
.011464,.01,
.011759,.009368,
.011939,.008695,
.012,.008,
.012,-.008,
.011939,-.008695,
.011759,-.009368,
.011464,-.01,
.011064,-.010571,
.010571,-.011064,
.01,-.011464,
.009368,-.011759,
.008695,-.011939,
.008,-.012,
0.0*
%
%ADD17MACRO17*%
%AMMACRO41*
4,1,40,.011,.007,
.011,-.007,
.010939,-.007695,
.010759,-.008368,
.010464,-.009,
.010064,-.009571,
.009571,-.010064,
.009,-.010464,
.008368,-.010759,
.007695,-.010939,
.007,-.011,
-.007,-.011,
-.007695,-.010939,
-.008368,-.010759,
-.009,-.010464,
-.009571,-.010064,
-.010064,-.009571,
-.010464,-.009,
-.010759,-.008368,
-.010939,-.007695,
-.011,-.007,
-.011,.007,
-.010939,.007695,
-.010759,.008368,
-.010464,.009,
-.010064,.009571,
-.009571,.010064,
-.009,.010464,
-.008368,.010759,
-.007695,.010939,
-.007,.011,
.007,.011,
.007695,.010939,
.008368,.010759,
.009,.010464,
.009571,.010064,
.010064,.009571,
.010464,.009,
.010759,.008368,
.010939,.007695,
.011,.007,
0.0*
%
%ADD41MACRO41*%
%AMMACRO26*
4,1,40,-.017,-.013,
-.017,.013,
-.016939,.013695,
-.016759,.014368,
-.016464,.015,
-.016064,.015571,
-.015571,.016064,
-.015,.016464,
-.014368,.016759,
-.013695,.016939,
-.013,.017,
.013,.017,
.013695,.016939,
.014368,.016759,
.015,.016464,
.015571,.016064,
.016064,.015571,
.016464,.015,
.016759,.014368,
.016939,.013695,
.017,.013,
.017,-.013,
.016939,-.013695,
.016759,-.014368,
.016464,-.015,
.016064,-.015571,
.015571,-.016064,
.015,-.016464,
.014368,-.016759,
.013695,-.016939,
.013,-.017,
-.013,-.017,
-.013695,-.016939,
-.014368,-.016759,
-.015,-.016464,
-.015571,-.016064,
-.016064,-.015571,
-.016464,-.015,
-.016759,-.014368,
-.016939,-.013695,
-.017,-.013,
0.0*
%
%ADD26MACRO26*%
%AMMACRO24*
4,1,40,.013,-.017,
-.013,-.017,
-.013695,-.016939,
-.014368,-.016759,
-.015,-.016464,
-.015571,-.016064,
-.016064,-.015571,
-.016464,-.015,
-.016759,-.014368,
-.016939,-.013695,
-.017,-.013,
-.017,.013,
-.016939,.013695,
-.016759,.014368,
-.016464,.015,
-.016064,.015571,
-.015571,.016064,
-.015,.016464,
-.014368,.016759,
-.013695,.016939,
-.013,.017,
.013,.017,
.013695,.016939,
.014368,.016759,
.015,.016464,
.015571,.016064,
.016064,.015571,
.016464,.015,
.016759,.014368,
.016939,.013695,
.017,.013,
.017,-.013,
.016939,-.013695,
.016759,-.014368,
.016464,-.015,
.016064,-.015571,
.015571,-.016064,
.015,-.016464,
.014368,-.016759,
.013695,-.016939,
.013,-.017,
0.0*
%
%ADD24MACRO24*%
%AMMACRO64*
4,1,6,.0135,.005,
.0065,.005,
-.0135,.025,
-.0135,-.025,
.0065,-.005,
.0135,-.005,
.0135,.005,
0.0*
%
%ADD64MACRO64*%
%AMMACRO29*
4,1,40,.012,.008,
.012,-.008,
.011939,-.008695,
.011759,-.009368,
.011464,-.01,
.011064,-.010571,
.010571,-.011064,
.01,-.011464,
.009368,-.011759,
.008695,-.011939,
.008,-.012,
-.008,-.012,
-.008695,-.011939,
-.009368,-.011759,
-.01,-.011464,
-.010571,-.011064,
-.011064,-.010571,
-.011464,-.01,
-.011759,-.009368,
-.011939,-.008695,
-.012,-.008,
-.012,.008,
-.011939,.008695,
-.011759,.009368,
-.011464,.01,
-.011064,.010571,
-.010571,.011064,
-.01,.011464,
-.009368,.011759,
-.008695,.011939,
-.008,.012,
.008,.012,
.008695,.011939,
.009368,.011759,
.01,.011464,
.010571,.011064,
.011064,.010571,
.011464,.01,
.011759,.009368,
.011939,.008695,
.012,.008,
0.0*
%
%ADD29MACRO29*%
%AMMACRO21*
4,1,40,-.007,.011,
.007,.011,
.007695,.010939,
.008368,.010759,
.009,.010464,
.009571,.010064,
.010064,.009571,
.010464,.009,
.010759,.008368,
.010939,.007695,
.011,.007,
.011,-.007,
.010939,-.007695,
.010759,-.008368,
.010464,-.009,
.010064,-.009571,
.009571,-.010064,
.009,-.010464,
.008368,-.010759,
.007695,-.010939,
.007,-.011,
-.007,-.011,
-.007695,-.010939,
-.008368,-.010759,
-.009,-.010464,
-.009571,-.010064,
-.010064,-.009571,
-.010464,-.009,
-.010759,-.008368,
-.010939,-.007695,
-.011,-.007,
-.011,.007,
-.010939,.007695,
-.010759,.008368,
-.010464,.009,
-.010064,.009571,
-.009571,.010064,
-.009,.010464,
-.008368,.010759,
-.007695,.010939,
-.007,.011,
0.0*
%
%ADD21MACRO21*%
%AMMACRO16*
4,1,40,.008,-.012,
-.008,-.012,
-.008695,-.011939,
-.009368,-.011759,
-.01,-.011464,
-.010571,-.011064,
-.011064,-.010571,
-.011464,-.01,
-.011759,-.009368,
-.011939,-.008695,
-.012,-.008,
-.012,.008,
-.011939,.008695,
-.011759,.009368,
-.011464,.01,
-.011064,.010571,
-.010571,.011064,
-.01,.011464,
-.009368,.011759,
-.008695,.011939,
-.008,.012,
.008,.012,
.008695,.011939,
.009368,.011759,
.01,.011464,
.010571,.011064,
.011064,.010571,
.011464,.01,
.011759,.009368,
.011939,.008695,
.012,.008,
.012,-.008,
.011939,-.008695,
.011759,-.009368,
.011464,-.01,
.011064,-.010571,
.010571,-.011064,
.01,-.011464,
.009368,-.011759,
.008695,-.011939,
.008,-.012,
0.0*
%
%ADD16MACRO16*%
%ADD66C,.012*%
%ADD67C,.014*%
%ADD68C,.015*%
%ADD69C,.025*%
%ADD70C,.016*%
%ADD71C,.005*%
%ADD72C,.006*%
%ADD73C,.007*%
%ADD74C,.0035*%
%ADD75C,.0049*%
%ADD76C,.00575*%
%ADD81R,.008X.02*%
%ADD79C,.03004*%
%ADD83O,.08402X.13502*%
%ADD82O,.08402X.10802*%
%ADD87R,.008X.019*%
%ADD80R,.019X.008*%
%ADD85C,.05204*%
%ADD78C,.04404*%
%ADD86C,.04804*%
%ADD84C,.06604*%
%ADD88C,.06804*%
%ADD89C,.08704*%
%ADD77R,.008X.008*%
G75*
%LPD*%
G75*
G36*
G01X26483Y752780D02*
X11125Y722062D01*
X10896D01*
X10750Y721916D01*
Y721708D01*
X10896Y721562D01*
X11000D01*
Y11000D01*
X109197D01*
Y40396D01*
X109343Y40437D01*
G03Y48147I-1075J3855D01*
G01X109197Y48188D01*
Y428627D01*
X117193D01*
Y3937D01*
G02X116260Y3004I-933J0D01*
G01X3937D01*
G02X3004Y3937I0J933D01*
G01Y723480D01*
G02X3103Y723897I933J-1D01*
G01X21284Y760260D01*
G02X22118Y760776I835J-417D01*
G01X386150D01*
G02X386984Y760260I-1J-933D01*
G01X405165Y723897D01*
G02X405264Y723480I-834J-418D01*
G01Y722062D01*
X397143D01*
X381785Y752780D01*
X379625D01*
X379565Y752853D01*
G03X348722Y752780I-15392J-12696D01*
G01X64663D01*
G03X33761I-15451J-12623D01*
G01X26483D01*
G37*
G36*
G01X98900Y507600D02*
X99068Y507768D01*
X99112Y507783D01*
G03X100117Y508788I-512J1517D01*
G01X100132Y508832D01*
X100300Y509000D01*
Y509087D01*
X103700Y512487D01*
Y554160D01*
X103705Y554182D01*
G03X103746Y554540I-1561J360D01*
G01Y555940D01*
G03X103705Y556298I-1602J-2D01*
G01X103700Y556320D01*
Y557261D01*
X102715Y558246D01*
X101398D01*
X100428Y559216D01*
Y561713D01*
X99656Y562485D01*
X96772D01*
X96525Y562238D01*
X92257D01*
X91812Y562683D01*
X90395D01*
X90365Y562693D01*
G03X89404Y562683I-466J-1428D01*
G01X89354D01*
X88912Y563125D01*
Y565108D01*
X89451Y565647D01*
X95869D01*
X95895Y565640D01*
G03X96313Y565584I420J1546D01*
G01X97913D01*
G03X98331Y565640I-2J1602D01*
G01X98357Y565647D01*
X99372D01*
X99398Y565640D01*
G03X99819Y565584I420J1545D01*
G01X101419D01*
G03X101840Y565640I1J1601D01*
G01X101866Y565647D01*
X109582D01*
X117097Y558132D01*
X120010D01*
G02X120408Y557693I0J-400D01*
G03X124792I2192J-213D01*
G02X125190Y558132I398J39D01*
G01X128830D01*
X133014Y562316D01*
X152685D01*
X153047Y561954D01*
X154102D01*
X154234Y562086D01*
X158000D01*
Y554782D01*
X155818Y552600D01*
X141574D01*
X140958Y551984D01*
Y549958D01*
X140900Y549900D01*
X130299D01*
X125064Y544665D01*
Y540664D01*
X117600Y533200D01*
Y524900D01*
X116000Y523300D01*
Y504300D01*
X109288Y497588D01*
X39543D01*
X27525Y509606D01*
Y576986D01*
X42086Y591547D01*
X49020D01*
X50640Y589928D01*
Y582973D01*
X50648Y582964D01*
Y582398D01*
X50953D01*
Y574783D01*
X51894Y573842D01*
Y572849D01*
X51890Y572829D01*
G03X51854Y572495I1566J-338D01*
G01Y571095D01*
G03X51859Y570982I1601J14D01*
G01Y570728D01*
X51339Y570208D01*
X48942D01*
X48932Y570209D01*
G03X48768Y570218I-170J-1593D01*
G01X46168D01*
G03X46004Y570209I6J-1602D01*
G01X45994Y570208D01*
X44920D01*
X44198Y569486D01*
Y566047D01*
X42001Y563850D01*
X40213D01*
X39514Y563151D01*
Y561823D01*
X39512Y561810D01*
G03X39498Y561600I1588J-211D01*
G01Y560200D01*
G03X39512Y559990I1602J1D01*
G01X39514Y559977D01*
Y539380D01*
X39508Y539355D01*
G03X39456Y538954I1550J-405D01*
G01Y537554D01*
G03X39508Y537153I1602J4D01*
G01X39514Y537128D01*
Y516657D01*
X48571Y507600D01*
X63271D01*
X63288Y507597D01*
G03X63551Y507576I259J1580D01*
G01X64951D01*
G03X65214Y507597I4J1601D01*
G01X65231Y507600D01*
X68558D01*
X68593Y507586D01*
G03X69178Y507476I583J1491D01*
G01X70578D01*
G03X71163Y507586I2J1601D01*
G01X71198Y507600D01*
X74405D01*
X74421Y507598D01*
G03X74673Y507578I252J1581D01*
G01X76073D01*
G03X76325Y507598I0J1601D01*
G01X76341Y507600D01*
X80032D01*
X80052Y507596D01*
G03X80368Y507564I319J1570D01*
G01X81768D01*
G03X82084Y507596I-3J1602D01*
G01X82104Y507600D01*
X98900D01*
G37*
G36*
G01X80340Y564561D02*
X76893D01*
X76467Y564987D01*
Y568710D01*
X75751Y569426D01*
X70746D01*
X69922Y570250D01*
Y571300D01*
X68722Y572500D01*
X67100D01*
X66500Y573100D01*
Y574500D01*
X67100Y575100D01*
X69060D01*
X69700Y575740D01*
Y578000D01*
X70000Y578300D01*
X71800D01*
X72100Y578000D01*
Y576200D01*
X72900Y575400D01*
X78825D01*
X80793Y573432D01*
Y565014D01*
X80340Y564561D01*
G37*
G36*
G01X57807Y574214D02*
X57424Y574597D01*
Y577379D01*
X56629Y578174D01*
X53734D01*
X52923Y578985D01*
Y582389D01*
X51841Y583471D01*
Y589609D01*
X53590Y591358D01*
X60121D01*
X62616Y588863D01*
Y584590D01*
G03X62148Y583800I433J-790D01*
G01Y581200D01*
G03X62616Y580410I901J0D01*
G01Y580051D01*
X62982Y579685D01*
X68413D01*
X69033Y579065D01*
Y576011D01*
X68699Y575677D01*
X66631D01*
X65168Y574214D01*
X57807D01*
G37*
G36*
G01X96364Y653316D02*
X48770D01*
X46815Y655271D01*
Y671419D01*
X49067Y673671D01*
X73494D01*
X74812Y672353D01*
X95334D01*
X98266Y669421D01*
Y655218D01*
X96364Y653316D01*
G37*
G36*
G01X126600Y502600D02*
X126200Y503000D01*
Y503735D01*
G03X126202Y503800I-1599J82D01*
G01Y505400D01*
G03X126200Y505465I-1601J-17D01*
G01Y508500D01*
X117367Y517333D01*
Y523002D01*
X118752Y524387D01*
Y530128D01*
X121233Y532609D01*
X122258D01*
X122298Y532591D01*
G03X124102I902J2009D01*
G01X124142Y532609D01*
X124428D01*
X125936Y534117D01*
Y538862D01*
X128325Y541251D01*
X128351Y541265D01*
G03X129235Y542149I-1051J1935D01*
G01X129249Y542174D01*
X134738Y547663D01*
X135372Y548297D01*
X141197D01*
X142200Y549300D01*
Y550906D01*
X142842Y551548D01*
X154752D01*
X155700Y550600D01*
Y547100D01*
X155442Y546842D01*
X149415D01*
X143530Y540957D01*
Y533330D01*
X141825Y531625D01*
Y521275D01*
X144400Y518700D01*
X144963D01*
X145013Y518667D01*
G03X145900Y518398I888J1333D01*
G01X147300D01*
G03X147484Y518409I-3J1602D01*
G01X147580Y518420D01*
X148100Y517900D01*
Y507488D01*
X146547D01*
G03X145834Y507321I-1J-1601D01*
G01X145792Y507300D01*
X138434D01*
X136821Y505687D01*
Y502768D01*
X136653Y502600D01*
X126600D01*
G37*
G36*
G01X118205Y559764D02*
X111167Y566802D01*
X89134D01*
X88839Y567097D01*
Y568375D01*
X88217Y568997D01*
X87204D01*
X87176Y569005D01*
G03X86324I-426J-1440D01*
G01X86296Y568997D01*
X84939D01*
X84710Y568768D01*
Y567031D01*
X84284Y566605D01*
X82500D01*
X82325Y566780D01*
Y570281D01*
X84444Y572400D01*
X86414D01*
X86434Y572396D01*
G03X87066I316J1468D01*
G01X87086Y572400D01*
X89563D01*
X89583Y572396D01*
G03X90215I316J1468D01*
G01X90235Y572400D01*
X90898D01*
X92649Y574151D01*
X98771D01*
X98803Y574140D01*
G03X99330Y574050I529J1512D01*
G01X100930D01*
G03X101457Y574140I-2J1602D01*
G01X101489Y574151D01*
X101951D01*
X102526Y574726D01*
Y575519D01*
X102527Y575527D01*
G03X102532Y575652I-1597J126D01*
G01Y577252D01*
G03X102527Y577377I-1602J-1D01*
G01X102526Y577385D01*
Y578422D01*
X101687Y579261D01*
X92384D01*
X91827Y579818D01*
Y588240D01*
X91853Y588266D01*
Y597536D01*
X92707Y598390D01*
X102391D01*
X104228Y596553D01*
Y596545D01*
X112763Y588010D01*
X121450D01*
X135280Y574180D01*
X148236D01*
X148246Y574179D01*
G03X148582Y574180I164J1493D01*
G01X148649D01*
X150585Y572244D01*
Y569019D01*
X151006Y568598D01*
X153629D01*
X153900Y568327D01*
Y564400D01*
X153500Y564000D01*
X131939D01*
X127703Y559764D01*
X118205D01*
G37*
G36*
G01X132499Y599401D02*
X131500Y600400D01*
X127449D01*
X127200Y600649D01*
Y604889D01*
X130411Y608100D01*
X131975D01*
G03X135695I1860J1520D01*
G01X140720D01*
X144015Y604805D01*
Y599655D01*
X143761Y599401D01*
X132499D01*
G37*
G36*
G01X116672Y625802D02*
X116072Y626402D01*
X115200D01*
Y629300D01*
X122000Y636100D01*
X127400D01*
X127500Y636000D01*
Y635665D01*
G03X127498Y635600I1599J-82D01*
G01Y634200D01*
G03X127500Y634135I1601J17D01*
G01Y631565D01*
G03X127498Y631500I1599J-82D01*
G01Y630100D01*
G03X127500Y630035I1601J17D01*
G01Y629400D01*
X126800Y628700D01*
X122100D01*
X119202Y625802D01*
X116672D01*
G37*
G36*
G01X117526Y599843D02*
X116902Y600467D01*
Y610877D01*
X117425Y611400D01*
X125600D01*
X125800Y611200D01*
Y600278D01*
X125365Y599843D01*
X117526D01*
G37*
G36*
G01X141534Y703659D02*
X128831D01*
X127602Y704888D01*
Y725540D01*
X128585Y726523D01*
X141903D01*
X142845Y725581D01*
Y704970D01*
X141534Y703659D01*
G37*
G36*
G01X95100Y702500D02*
X94459Y701859D01*
X94363Y701870D01*
G03X93023Y701600I-257J-2187D01*
G01X85000D01*
X83500Y703100D01*
Y708600D01*
X84900Y710000D01*
X85069D01*
X85071Y709998D01*
X88599D01*
G03X90521I961J2202D01*
G01X93502D01*
X95100Y708400D01*
Y702500D01*
G37*
G36*
G01X97800Y671900D02*
X96100Y673600D01*
X90500D01*
X90102Y673998D01*
Y678398D01*
X90100Y678399D01*
Y678400D01*
X88102Y680398D01*
Y685402D01*
X88700Y686000D01*
X100200D01*
X101800Y684400D01*
Y672900D01*
X100800Y671900D01*
X97800D01*
G37*
G36*
G01X76100Y673600D02*
X74300Y675400D01*
Y683000D01*
X74329Y684729D01*
X75500Y685900D01*
X86400D01*
X86900Y685400D01*
Y682265D01*
G03X86898Y682200I1599J-82D01*
G01Y680600D01*
G03X86900Y680535I1601J17D01*
G01Y679900D01*
X88898Y677902D01*
Y676000D01*
G03X88900Y675935I1601J17D01*
G01Y674000D01*
X88500Y673600D01*
X76100D01*
G37*
G36*
G01X274497Y665876D02*
X284920Y676299D01*
X284951Y676314D01*
G03X285719Y676924I-951J1986D01*
G01X304223D01*
X305900Y675247D01*
Y670602D01*
G03X305656Y670180I1248J-1003D01*
G01X305641Y670141D01*
X305100Y669600D01*
X299204D01*
X299153Y669724D01*
G03X295083I-2035J-842D01*
G01X295032Y669600D01*
X293632D01*
X293177Y669145D01*
G02X292541Y669239I-283J283D01*
G03X289561Y666259I-1941J-1039D01*
G02X289655Y665623I-189J-353D01*
G01X276738Y652706D01*
X273365D01*
X273363Y652704D01*
X259679D01*
X251951Y660432D01*
X248746D01*
X248453Y660725D01*
X232986D01*
G03X230014I-1486J-1625D01*
G01X188625D01*
X174702Y646802D01*
X145398D01*
X138276Y653924D01*
X137682D01*
X137681Y653926D01*
X122165D01*
X122128Y653940D01*
G03X122012Y653984I-839J-2036D01*
G01X121968Y653999D01*
X120759Y655208D01*
Y662059D01*
X121400Y662700D01*
X137643D01*
X139100Y661243D01*
X149000D01*
X155743Y654500D01*
X172622D01*
X188240Y670118D01*
X244520D01*
X246334Y668304D01*
X247076D01*
X247108Y668293D01*
G03X248542I717J2082D01*
G01X248574Y668304D01*
X253766D01*
X260953Y661117D01*
X260965Y661098D01*
G03X261650Y660413I1861J1176D01*
G01X261669Y660401D01*
X262500Y659570D01*
X268191D01*
X272124Y663503D01*
X272212Y663500D01*
G03X274500Y665788I88J2200D01*
G01X274497Y665876D01*
G37*
G36*
G01X200144Y462209D02*
X196450Y465903D01*
Y469050D01*
X197000Y469600D01*
X204400D01*
X205300Y468700D01*
X211253D01*
X211263Y468699D01*
G03X211418Y468692I150J1594D01*
G01X212818D01*
G03X212973Y468699I5J1601D01*
G01X212983Y468700D01*
X217200D01*
X217400Y468500D01*
Y468165D01*
G03X217398Y468100I1599J-82D01*
G01Y466500D01*
G03X217400Y466435I1601J17D01*
G01Y465900D01*
X217100Y465600D01*
X213003D01*
X212290Y464887D01*
X209603Y462209D01*
X200144D01*
G37*
G36*
G01X196566Y511454D02*
X196710Y511597D01*
X196712Y511599D01*
G03X195475Y515385I-1512J1601D01*
G01X195300Y515407D01*
Y518500D01*
X195900Y519100D01*
X221700D01*
X223500Y517300D01*
Y515100D01*
X225100Y513500D01*
X230600D01*
X230976Y513124D01*
Y510381D01*
X230970Y510357D01*
G03Y509243I2130J-557D01*
G01X230976Y509219D01*
Y506734D01*
X230956Y506693D01*
G03X230798Y506000I1444J-694D01*
G01Y504600D01*
G03X230807Y504440I1601J10D01*
G02X230409Y504000I-398J-40D01*
G01X228824D01*
X228548Y504276D01*
X228554Y504366D01*
G03X225946Y506677I-2197J148D01*
G01X225842Y506658D01*
X221400Y511100D01*
X202739D01*
X202720Y511120D01*
X200703D01*
G03X198299I-1202J-1845D01*
G01X196900D01*
X196566Y511454D01*
G37*
G36*
G01X183681Y556711D02*
X182175Y558217D01*
Y561165D01*
X183077Y562067D01*
Y565633D01*
X182595Y566115D01*
X179488D01*
X178855Y566748D01*
Y569215D01*
X179770Y570130D01*
Y577590D01*
X180378Y578198D01*
X188158D01*
X188159Y578200D01*
X188370D01*
X189980Y579810D01*
Y584460D01*
X190330Y584810D01*
X194330D01*
X194772Y585252D01*
X196610D01*
X196646Y585238D01*
G03X197684I519J1302D01*
G01X197720Y585252D01*
X198546D01*
X198841Y584957D01*
Y581944D01*
X196700Y579803D01*
X194103D01*
X192654Y578354D01*
Y575778D01*
X193165Y575267D01*
X198079D01*
X199170Y574176D01*
X199204D01*
X199999Y573381D01*
Y567137D01*
X198651Y565789D01*
X195829D01*
X195180Y565140D01*
Y562083D01*
X194683Y561586D01*
X192713D01*
X191990Y560863D01*
Y557436D01*
X191265Y556711D01*
X183681D01*
G37*
G36*
G01X164500Y554478D02*
Y552608D01*
X164481Y552568D01*
G03X164346Y551934I1267J-601D01*
G01X164348Y551848D01*
X163500Y551000D01*
X161500D01*
X160787Y551713D01*
X160801Y551812D01*
G03X160500Y552890I-1389J193D01*
G01Y554190D01*
G03X160544Y555994I-1051J928D01*
G01X160500Y556049D01*
Y556400D01*
X161100Y557000D01*
X161998D01*
X162037Y556983D01*
G03X163159I561J1285D01*
G01X163198Y557000D01*
X164000D01*
X164500Y556500D01*
Y555758D01*
X164481Y555718D01*
G03Y554518I1267J-600D01*
G01X164500Y554478D01*
G37*
G36*
G01X208443Y558143D02*
X207200Y556900D01*
X193679D01*
X192921Y557658D01*
Y560325D01*
X193576Y560980D01*
X202190D01*
X202222Y560948D01*
G03X204906Y561748I1321J470D01*
G01X204900Y561771D01*
Y564215D01*
X204906Y564238D01*
G03Y564898I-1363J330D01*
G01X204900Y564921D01*
Y567830D01*
X206070Y569000D01*
X207422D01*
X207442Y568996D01*
G03X207668Y568964I379J1864D01*
G01X207742Y568958D01*
X208515Y568185D01*
X208486Y568074D01*
G03X208493Y567337I1356J-356D01*
G01X208500Y567310D01*
Y564974D01*
X208493Y564947D01*
G03Y564187I1349J-380D01*
G01X208500Y564160D01*
Y561824D01*
X208493Y561797D01*
G03Y561037I1349J-380D01*
G01X208500Y561010D01*
Y558675D01*
X208493Y558648D01*
G03X208441Y558229I1349J-380D01*
G01X208443Y558143D01*
G37*
G36*
G01X162533Y525656D02*
X160038Y523162D01*
X159100D01*
X158892Y522954D01*
X158864Y522940D01*
G03X158161Y522237I725J-1428D01*
G01X158147Y522209D01*
X158000Y522062D01*
Y521712D01*
X157999Y521700D01*
G03X157988Y521512I1590J-187D01*
G01Y520112D01*
G03X157999Y519924I1601J-1D01*
G01X158000Y519912D01*
Y517000D01*
X159200Y515800D01*
Y512253D01*
X158447Y511500D01*
X154600D01*
X154550Y511550D01*
X154150D01*
X154052Y511648D01*
Y520899D01*
X155344Y522191D01*
G03X156597Y523429I-944J2209D01*
G01X156612Y523463D01*
X156949Y523800D01*
Y526437D01*
X157242Y526730D01*
X160030D01*
X162333Y529033D01*
X162436Y529014D01*
G03X162600Y528998I169J885D01*
G01X164000D01*
G03X164568Y529200I-1J902D01*
G01X168800D01*
X169600Y530000D01*
Y531500D01*
X170400Y532300D01*
X172200D01*
X172700Y531800D01*
Y525500D01*
X172300Y525100D01*
Y519946D01*
X172292Y519918D01*
G03Y518648I2108J-635D01*
G01X172300Y518620D01*
Y513300D01*
X171400Y512400D01*
X169800D01*
X169300Y512900D01*
Y516335D01*
G03X169302Y516400I-1599J82D01*
G01Y517800D01*
G03X169300Y517865I-1601J-17D01*
G01Y519735D01*
G03X169302Y519800I-1599J82D01*
G01Y521200D01*
G03X169300Y521265I-1601J-17D01*
G01Y524656D01*
X168300Y525656D01*
X168160D01*
X168102Y525710D01*
G03X165042Y525656I-1502J-1610D01*
G01X162533D01*
G37*
G36*
G01X225900Y514900D02*
X224702Y516099D01*
Y517798D01*
X224700Y517799D01*
Y518200D01*
X221800Y521100D01*
X190800D01*
X190000Y521900D01*
Y526000D01*
X190898Y526898D01*
X192289D01*
G03X195222Y527105I1361J1602D01*
G02X195791Y527135I299J-265D01*
G03X196400Y526898I609J664D01*
G01X197800D01*
G03X198556Y527309I0J901D01*
G01X198615Y527400D01*
X211488D01*
X212428Y526460D01*
X222417D01*
X225688Y523189D01*
X232637D01*
X233200Y522626D01*
Y516400D01*
X231700Y514900D01*
X225900D01*
G37*
G36*
G01X171842Y572763D02*
X170314Y574292D01*
X170210D01*
X170198Y574304D01*
X168100D01*
X167825Y574579D01*
Y575786D01*
X168027Y575988D01*
X168136D01*
G03X170148Y576530I762J1177D01*
G01X170162Y576558D01*
X170296Y576692D01*
Y577066D01*
G03Y577264I-1398J99D01*
G01Y580216D01*
G03Y580414I-1398J99D01*
G01Y583365D01*
G03Y583563I-1398J99D01*
G01Y586515D01*
G03Y586713I-1398J99D01*
G01Y588076D01*
X170526Y588306D01*
X173521D01*
X173633Y588194D01*
Y573073D01*
X173323Y572763D01*
X171842D01*
G37*
G36*
G01X174529Y578687D02*
X174167Y579049D01*
Y588297D01*
X174134Y588330D01*
Y588402D01*
X173729Y588808D01*
X173656D01*
X173633Y588831D01*
X168208D01*
X167743Y589296D01*
Y590148D01*
X168057Y590462D01*
X176460D01*
X176801Y590122D01*
Y578860D01*
X176628Y578687D01*
X175784D01*
X175754Y578696D01*
G03X174842I-456J-1430D01*
G01X174812Y578687D01*
X174529D01*
G37*
G36*
G01X204150Y572930D02*
X201470D01*
X198600Y575800D01*
X193600D01*
X193200Y576200D01*
Y577600D01*
X194850Y579250D01*
X197250D01*
X199910Y581910D01*
Y584390D01*
X200706Y585186D01*
X204279D01*
X204530Y584935D01*
Y581916D01*
X204335Y581721D01*
X202781D01*
X202090Y581030D01*
Y576500D01*
X203010Y575580D01*
X204440D01*
X204830Y575190D01*
Y573610D01*
X204150Y572930D01*
G37*
G36*
G01X187950Y578700D02*
X177895D01*
X177503Y579092D01*
Y587303D01*
X178300Y588100D01*
X181200D01*
X184300Y585000D01*
X188550D01*
X188820Y584730D01*
Y579570D01*
X187950Y578700D01*
G37*
G36*
G01X247139Y621200D02*
X246740Y621599D01*
Y626348D01*
X246859Y626467D01*
X248330D01*
X249087Y627224D01*
Y630874D01*
X249429Y631216D01*
X253583D01*
X254567Y632200D01*
X256400D01*
X256726Y631874D01*
X256707Y631771D01*
G03X256789Y630661I2166J-398D01*
G01X256800Y630630D01*
Y625100D01*
X252900Y621200D01*
X247139D01*
G37*
G36*
G01X254052Y607600D02*
X253607Y608045D01*
Y611457D01*
X252714Y612350D01*
X247703D01*
X247677Y612357D01*
G03X246499I-589J-2121D01*
G01X246473Y612350D01*
X240250D01*
X238000Y614600D01*
Y619189D01*
X238689Y619878D01*
X256005D01*
X256676Y619207D01*
Y614596D01*
X256185Y614105D01*
Y607960D01*
X255825Y607600D01*
X254052D01*
G37*
G36*
G01X281016Y699820D02*
X278220Y702616D01*
Y716788D01*
X280404Y718972D01*
X303896D01*
G03X307222I1663J2001D01*
G01X308896D01*
G03X312222I1663J2001D01*
G01X323887D01*
X327120Y715739D01*
Y705120D01*
X321820Y699820D01*
X281016D01*
G37*
G36*
G01X903913Y760260D02*
X922094Y723897D01*
G02X922193Y723480I-834J-418D01*
G01Y3937D01*
G02X921260Y3004I-933J0D01*
G01X291457D01*
G02X290524Y3937I0J933D01*
G01Y141798D01*
X298520D01*
Y11000D01*
X349757D01*
X355159Y5598D01*
X670434D01*
X675836Y11000D01*
X914197D01*
Y721812D01*
X898714Y752780D01*
X891435D01*
G03X860592Y752853I-15451J-12623D01*
G01X860532Y752780D01*
X857457D01*
Y747562D01*
X857443Y747526D01*
G03X857457Y732752I18541J-7369D01*
G01Y633858D01*
G02X842520Y618921I-14937J0D01*
G01X627656D01*
G03X596812Y618994I-15452J-12622D01*
G01X596752Y618921D01*
X594593D01*
X579110Y587953D01*
Y488787D01*
G03X571888Y479496I11441J-16346D01*
G02X571114Y479638I-374J142D01*
G01Y589621D01*
G02X571213Y590038I933J-1D01*
G01X589394Y626401D01*
G02X590228Y626917I835J-417D01*
G01X842520D01*
G03X849461Y633858I0J6941D01*
G01Y759843D01*
G02X850394Y760776I933J0D01*
G01X903079D01*
G02X903913Y760260I-1J-933D01*
G37*
G36*
G01X351850Y19961D02*
X333500Y38311D01*
Y97500D01*
X336000Y100000D01*
X364000D01*
X366500Y97500D01*
Y44000D01*
X374884Y35616D01*
Y20610D01*
X374235Y19961D01*
X351850D01*
G37*
G36*
G01X320998Y194301D02*
Y180400D01*
G02X320614Y180000I-400J0D01*
G03X319187Y179400I85J-2200D01*
G01X314500D01*
X314100Y179800D01*
Y188000D01*
X315000Y188900D01*
Y190422D01*
X315008D01*
Y197326D01*
X314975D01*
X314300Y198000D01*
X308500D01*
X307900Y198600D01*
Y200300D01*
X306700Y201500D01*
X304500D01*
X304100Y201900D01*
Y206900D01*
X304500Y207300D01*
X313200D01*
X318098Y202402D01*
Y195802D01*
X318100Y195801D01*
Y195600D01*
X319200Y194500D01*
X319401D01*
X319402Y194498D01*
X320801D01*
X320998Y194301D01*
G37*
G36*
G01X322500Y179400D02*
X322200Y179700D01*
Y195000D01*
X321500Y195700D01*
X319900D01*
X319300Y196300D01*
Y203300D01*
X319999Y203998D01*
X324801D01*
X328798Y200002D01*
Y189002D01*
X328800Y189001D01*
Y179700D01*
X328500Y179400D01*
X322500D01*
G37*
G36*
G01X304000Y188400D02*
X303600Y188800D01*
Y196500D01*
X303900Y196800D01*
X308001D01*
X308002Y196798D01*
X313401D01*
X313798Y196401D01*
Y189498D01*
X312700Y188400D01*
X304000D01*
G37*
G36*
G01X330900Y188600D02*
X330000Y189500D01*
Y200600D01*
X325400Y205200D01*
X317600D01*
X306700Y216100D01*
X304400D01*
X304000Y216500D01*
Y224200D01*
X304500Y224700D01*
X306501D01*
X306502Y224698D01*
X321201D01*
X321700Y224200D01*
Y219793D01*
X321695Y219771D01*
G03Y218797I2147J-487D01*
G01X321700Y218775D01*
Y216900D01*
X320900Y216100D01*
Y214462D01*
X320899Y214454D01*
G03Y214014I2593J-220D01*
G01X320900Y214006D01*
Y213100D01*
X322400Y211600D01*
X335800D01*
X339100Y208300D01*
Y189300D01*
X338400Y188600D01*
X330900D01*
G37*
G36*
G01X307000Y225900D02*
X306500Y226400D01*
X304300D01*
X304100Y226600D01*
Y228700D01*
X304200Y228800D01*
X305041D01*
X305073Y228789D01*
G03X306491I709J2085D01*
G01X306523Y228800D01*
X307200D01*
X308050Y229650D01*
Y231050D01*
X315800Y238800D01*
X324000D01*
X324900Y237900D01*
Y226100D01*
X324700Y225900D01*
X307000D01*
G37*
G36*
G01X334300Y216200D02*
X333400Y217100D01*
Y221500D01*
X333386Y221514D01*
Y221536D01*
X333365D01*
X333100Y221800D01*
X327300D01*
X326200Y222900D01*
Y238500D01*
X326600Y238900D01*
X331700D01*
X332700Y237900D01*
Y237594D01*
G03Y237406I2400J-94D01*
G01Y231600D01*
X333600Y230700D01*
X336000D01*
X337000Y229700D01*
Y217100D01*
X336100Y216200D01*
X334300D01*
G37*
G36*
G01X377000Y618400D02*
Y612319D01*
G03X378119Y608152I1965J-1706D01*
G01X378163Y608137D01*
X379000Y607300D01*
X380500D01*
X383000Y604800D01*
Y601500D01*
X382200Y600700D01*
X380765D01*
G03X380700Y600702I-82J-1599D01*
G01X379300D01*
G03X379235Y600700I17J-1601D01*
G01X379100D01*
X377795Y602005D01*
X363844D01*
X363539Y602310D01*
X358090D01*
X353600Y606800D01*
Y611535D01*
G03X353602Y611600I-1599J82D01*
G01Y613600D01*
G03X353600Y613665I-1601J-17D01*
G01Y617000D01*
X357500Y620900D01*
X364500D01*
X367231Y623631D01*
X370769D01*
X371013Y623387D01*
Y620987D01*
X371900Y620100D01*
X374500D01*
X375700Y618900D01*
X376500D01*
X377000Y618400D01*
G37*
G36*
G01X295744Y629623D02*
X295700Y629763D01*
G03X292285Y630866I-2100J-663D01*
G01X292146Y630763D01*
X291400Y631509D01*
Y642828D01*
X293420Y644848D01*
X329680D01*
G02X330067Y644349I0J-400D01*
G03X334203Y642884I2133J-549D01*
G02X334849Y643001I364J-166D01*
G01X336600Y641250D01*
Y631203D01*
X335020Y629623D01*
X295744D01*
G37*
G36*
G01X353900Y623200D02*
X348400D01*
X345900Y625700D01*
Y633500D01*
X346900Y634500D01*
X355800D01*
X357000Y633300D01*
Y626300D01*
X353900Y623200D01*
G37*
G36*
G01X381000Y35000D02*
X385500Y30500D01*
Y20938D01*
X384573Y20011D01*
X376775D01*
X376100Y20686D01*
Y30235D01*
G03X376102Y30300I-1599J82D01*
G01Y31700D01*
G03X376100Y31765I-1601J-17D01*
G01Y34100D01*
X377000Y35000D01*
X381000D01*
G37*
G36*
G01X405264Y702285D02*
X397268D01*
Y719900D01*
X405264D01*
Y702285D01*
G37*
G36*
G01X513522Y50559D02*
X510546Y47583D01*
X507741D01*
X507692Y47712D01*
G03X503982Y45475I-2059J-780D01*
G01X504107Y45334D01*
X503676Y44903D01*
X498051D01*
X498043Y44904D01*
G03X497918Y44908I-114J-1597D01*
G01X496518D01*
G03X496393Y44904I-11J-1601D01*
G01X496385Y44903D01*
X495052D01*
X490374Y49581D01*
Y55768D01*
X491057Y56451D01*
X491793D01*
X491816Y56445D01*
G03X492200Y56398I385J1555D01*
G01X494800D01*
G03X495184Y56445I-1J1602D01*
G01X495207Y56451D01*
X497182D01*
X497198Y56449D01*
G03X497450Y56428I259J1580D01*
G01X498850D01*
G03X499102Y56449I-7J1601D01*
G01X499118Y56451D01*
X500962D01*
G03X503638I1338J1749D01*
G01X504793D01*
X504816Y56445D01*
G03X505200Y56398I385J1555D01*
G01X507800D01*
G03X508184Y56445I-1J1602D01*
G01X508207Y56451D01*
X509590D01*
G03X510800Y55898I1211J1049D01*
G01X512200D01*
G03X512742Y55993I-1J1602D01*
G01X512861Y56036D01*
X513596Y55301D01*
X513606Y55235D01*
G03X514493Y53769I2179J317D01*
G01Y52741D01*
G03X513512Y50655I1207J-1841D01*
G01X513522Y50559D01*
G37*
G36*
G01X581846Y65873D02*
X543373Y27400D01*
X506900D01*
X506868Y27432D01*
X502366D01*
X497217Y32581D01*
X492868D01*
X492544Y32905D01*
X492549Y32994D01*
G03X492552Y33081I-1599J99D01*
G01Y34481D01*
G03X492544Y34636I-1602J-5D01*
G01X492543Y34646D01*
Y36940D01*
X492545Y36954D01*
G03X492562Y37183I-1585J233D01*
G01Y38583D01*
G03X492545Y38812I-1602J-4D01*
G01X492543Y38826D01*
Y39175D01*
X493182Y39814D01*
X494343D01*
X494360Y39797D01*
X495244D01*
X496121Y40674D01*
Y43508D01*
X496315Y43702D01*
X504174D01*
X504176Y43704D01*
X506204D01*
X508800Y46300D01*
X513898D01*
X516413Y48815D01*
X516455Y48830D01*
G03X517769Y50144I-755J2069D01*
G01X517784Y50186D01*
X523349Y55751D01*
X533051D01*
X550816Y73516D01*
X551550D01*
X555490Y77456D01*
X582996D01*
X583004Y77464D01*
X593545D01*
X595994Y75015D01*
Y66717D01*
X595150Y65873D01*
X581846D01*
G37*
G36*
G01X518990Y72554D02*
X515260Y68824D01*
Y62118D01*
X513990Y60848D01*
X510992D01*
X509596Y62244D01*
Y64167D01*
X509597Y64175D01*
G03X509602Y64300I-1597J126D01*
G01Y65700D01*
G03X509597Y65825I-1602J-1D01*
G01X509596Y65833D01*
Y66603D01*
X508968Y67231D01*
X508471D01*
X508444Y67239D01*
G03X508000Y67302I-445J-1539D01*
G01X506600D01*
G03X506156Y67239I1J-1602D01*
G01X506129Y67231D01*
X501563D01*
X500540Y66208D01*
X490192D01*
X488900Y67500D01*
Y71700D01*
G03Y75100I-1400J1700D01*
G01Y77900D01*
X490649Y79648D01*
X514901D01*
X514913Y79660D01*
X518370D01*
X518990Y79040D01*
Y78465D01*
G03X518988Y78400I1599J-82D01*
G01Y77000D01*
G03X518990Y76935I1601J17D01*
G01Y72554D01*
G37*
G36*
G01X579110Y188976D02*
G02X559273Y177976I-12969J0D01*
G01X554772D01*
Y185972D01*
X562179D01*
G03X571114Y188976I3962J3004D01*
G01Y294875D01*
G02X571834Y295115I400J0D01*
G03X579110Y289124I15962J11971D01*
G01Y188976D01*
G37*
G36*
G01X610853Y38969D02*
X602101D01*
X601112Y39958D01*
Y49592D01*
X602595Y51075D01*
X609511D01*
X612123Y48463D01*
Y40239D01*
X610853Y38969D01*
G37*
G36*
G01X571114Y319299D02*
Y465244D01*
G02X571888Y465386I400J0D01*
G03X579110Y456095I18663J7055D01*
G01Y325050D01*
G03X571834Y319059I8686J-17962D01*
G02X571114Y319299I-320J240D01*
G37*
G36*
G01X670247Y23107D02*
X652547D01*
X651547Y24107D01*
Y34107D01*
X652847Y35407D01*
X670547D01*
X670947Y35007D01*
Y23807D01*
X670247Y23107D01*
G37*
G36*
G01X648047Y36607D02*
X646547Y38107D01*
Y54007D01*
X647647Y55107D01*
X669247D01*
X672047Y52307D01*
Y37807D01*
X670848Y36608D01*
X652349D01*
X652348Y36607D01*
X648047D01*
G37*
G36*
G01X662752Y480957D02*
X661908Y481800D01*
Y495174D01*
X662938Y496203D01*
X668166D01*
X668800Y495569D01*
Y481566D01*
X668191Y480957D01*
X662752D01*
G37*
G36*
G01X674980Y465186D02*
X672618Y467548D01*
Y473156D01*
X674049Y474587D01*
X683380D01*
X683386Y474593D01*
X686622D01*
X689407Y477378D01*
Y486557D01*
X689399D01*
Y488152D01*
X689400Y488153D01*
Y495644D01*
G03X689402Y495709I-1599J82D01*
G01Y497309D01*
G03X689400Y497374I-1601J-17D01*
G01Y499344D01*
G03X689402Y499409I-1599J82D01*
G01Y501009D01*
G03X689400Y501074I-1601J-17D01*
G01Y502909D01*
X690000Y503509D01*
X694900D01*
X695700Y502709D01*
Y487721D01*
X692089Y484110D01*
Y479293D01*
X694556Y476826D01*
X696112D01*
X696343Y476595D01*
Y470703D01*
X695780Y470140D01*
X693199D01*
X692092Y471247D01*
X688189D01*
X685969Y469027D01*
Y466163D01*
X684992Y465186D01*
X674980D01*
G37*
G36*
G01X697275Y470486D02*
X696975Y470786D01*
Y475686D01*
X696925Y475736D01*
Y477036D01*
X696575Y477386D01*
X695275D01*
X692975Y479686D01*
Y484074D01*
X693678Y484777D01*
X696831D01*
X697440Y484168D01*
Y480490D01*
X697444Y480486D01*
Y479217D01*
X698675Y477986D01*
Y470686D01*
X698475Y470486D01*
X697275D01*
G37*
G36*
G01X736109Y484771D02*
X715148Y505732D01*
X690674D01*
X689652Y504710D01*
X689502D01*
X688198Y503407D01*
Y485356D01*
X688200D01*
Y478100D01*
X686100Y476000D01*
X672600D01*
X670000Y478600D01*
Y481067D01*
X670002Y481068D01*
Y481483D01*
X670005Y481501D01*
G03X670034Y481802I-1573J303D01*
G01Y483402D01*
G03X670005Y483703I-1602J-2D01*
G01X670002Y483721D01*
Y485583D01*
X670005Y485601D01*
G03X670034Y485902I-1573J303D01*
G01Y487502D01*
G03X670005Y487803I-1602J-2D01*
G01X670002Y487821D01*
Y489583D01*
X670005Y489601D01*
G03X670034Y489902I-1573J303D01*
G01Y491502D01*
G03X670005Y491803I-1602J-2D01*
G01X670002Y491821D01*
Y493083D01*
X670005Y493101D01*
G03X670034Y493402I-1573J303D01*
G01Y495002D01*
G03X670005Y495303I-1602J-2D01*
G01X670002Y495321D01*
Y496067D01*
X670000Y496068D01*
Y506929D01*
X677070Y514000D01*
X713689D01*
X716197Y516508D01*
X741815D01*
X744273Y518966D01*
Y523991D01*
X746581Y526299D01*
X755462D01*
G03X755575Y526294I127J1596D01*
G01X757175D01*
G03X757288Y526299I-14J1601D01*
G01X759462D01*
G03X759575Y526294I127J1596D01*
G01X761175D01*
G03X761295Y526299I-7J1602D01*
G01X761384D01*
X761584Y526098D01*
X774702D01*
X776200Y524600D01*
X781700D01*
X782400Y523900D01*
Y520465D01*
G03X782002Y519085I2204J-1383D01*
G01Y519002D01*
X780800Y517800D01*
Y517146D01*
G03X780266Y515952I1068J-1194D01*
G01Y514352D01*
G03X780741Y513214I1601J0D01*
G01X780800Y513155D01*
Y513000D01*
X781075Y512725D01*
X807171D01*
X807968Y513522D01*
X833862D01*
X841500Y505884D01*
Y492918D01*
X840957Y492375D01*
X831325D01*
X826200Y497500D01*
X797360D01*
X784631Y484771D01*
X736109D01*
G37*
G36*
G01X696800Y441000D02*
X695700Y442100D01*
Y454235D01*
G03X695702Y454300I-1599J82D01*
G01Y455700D01*
G03X695700Y455765I-1601J-17D01*
G01Y456500D01*
X694300Y457900D01*
Y463600D01*
X694700Y464000D01*
X698300D01*
X698400Y463900D01*
Y451100D01*
X699350Y450150D01*
Y441250D01*
X699100Y441000D01*
X696800D01*
G37*
G36*
G01X694935Y515300D02*
X681542D01*
X681026Y515816D01*
Y521190D01*
X681724Y521888D01*
X702556D01*
X703301Y522633D01*
X705835D01*
X707214Y521254D01*
Y516593D01*
X706353Y515732D01*
X695367D01*
X694935Y515300D01*
G37*
G36*
G01X762082Y527300D02*
X761876Y527506D01*
X746160D01*
X745515Y528151D01*
Y531375D01*
X743054Y533836D01*
X737930D01*
X736893Y534873D01*
Y538927D01*
X737284Y539318D01*
X747689D01*
X749199Y537808D01*
Y535806D01*
X751304Y533701D01*
X751900D01*
G03X756066Y535407I1900J1299D01*
G01X756047Y535510D01*
X757277Y536740D01*
X757753D01*
X757799Y536713D01*
G03X758605Y536496I805J1384D01*
G01X760005D01*
G03X760811Y536713I1J1601D01*
G01X760857Y536740D01*
X761153D01*
X761199Y536713D01*
G03X762005Y536496I805J1384D01*
G01X763405D01*
G03X763611Y536509I2J1601D01*
G02X763828Y536369I26J-198D01*
G03X768057Y536420I2107J640D01*
G01X768071Y536471D01*
X768900Y537300D01*
Y538763D01*
X768922Y538805D01*
G03X769096Y539531I-1428J726D01*
G01Y540931D01*
G03X769090Y541066I-1602J-4D01*
G02X769488Y541500I398J34D01*
G01X780400D01*
X782600Y539300D01*
Y527800D01*
X782100Y527300D01*
X775074D01*
G03X774253Y527526I-820J-1375D01*
G01X772653D01*
G03X771876Y527325I0J-1602D01*
G01X771830Y527300D01*
X771076D01*
X771030Y527325D01*
G03X770253Y527526I-777J-1401D01*
G01X768653D01*
G03X767876Y527325I0J-1602D01*
G01X767830Y527300D01*
X767076D01*
X767030Y527325D01*
G03X766253Y527526I-777J-1401D01*
G01X764653D01*
G03X763832Y527300I-1J-1601D01*
G01X762082D01*
G37*
G36*
G01X783632Y513945D02*
X783622Y513946D01*
G03X783467Y513954I-160J-1594D01*
G01X782002D01*
Y517302D01*
X783602Y518902D01*
Y521143D01*
X806478D01*
X807768Y519853D01*
Y515202D01*
X806511Y513945D01*
X795632D01*
X795622Y513946D01*
G03X795467Y513954I-160J-1594D01*
G01X793867D01*
G03X793712Y513946I5J-1602D01*
G01X793702Y513945D01*
X791632D01*
X791622Y513946D01*
G03X791467Y513954I-160J-1594D01*
G01X789867D01*
G03X789712Y513946I5J-1602D01*
G01X789702Y513945D01*
X787632D01*
X787622Y513946D01*
G03X787467Y513954I-160J-1594D01*
G01X785867D01*
G03X785712Y513946I5J-1602D01*
G01X785702Y513945D01*
X783632D01*
G37*
G36*
G01X859088Y185081D02*
X858026Y186143D01*
Y197231D01*
X858876Y198081D01*
X875055D01*
X875738Y197398D01*
X880060D01*
X881691Y195766D01*
Y185634D01*
X881138Y185081D01*
X859088D01*
G37*
G36*
G01X858390Y268486D02*
X856620Y270256D01*
Y311504D01*
X861905Y316789D01*
X882016D01*
X885202Y313603D01*
Y270782D01*
X885200Y270768D01*
G03X885184Y270545I1586J-226D01*
G01Y268945D01*
G03X885187Y268852I1602J5D01*
G01X885192Y268762D01*
X884916Y268486D01*
X858390D01*
G37*
G36*
G01X875992Y377572D02*
X854720D01*
X853334Y378958D01*
Y387262D01*
X854622Y388550D01*
X876213D01*
X877320Y387443D01*
Y378900D01*
X875992Y377572D01*
G37*
G36*
G01X813678Y419637D02*
X813652Y419663D01*
Y426851D01*
X813466Y427037D01*
X809959D01*
X809261Y426339D01*
Y424013D01*
X808260Y423012D01*
X807738D01*
G03X807625Y423016I-113J-1597D01*
G01X806025D01*
G03X805912Y423012I0J-1601D01*
G01X805587D01*
X805239Y423360D01*
Y433381D01*
X807695Y435837D01*
X812625D01*
X812737Y435728D01*
X814608Y433857D01*
Y429229D01*
X814607Y429217D01*
G03X814594Y429021I1588J-204D01*
G01Y427621D01*
G03X814964Y426598I1602J1D01*
G01Y419691D01*
X814910Y419637D01*
X813678D01*
G37*
G36*
G01X816000Y402000D02*
X816300Y401700D01*
Y400700D01*
X816800Y400200D01*
X818900D01*
X820400Y398700D01*
Y393100D01*
X819900Y392600D01*
X814100D01*
X813700Y393000D01*
Y395400D01*
X813704Y395419D01*
G03Y396381I-2404J481D01*
G01X813700Y396400D01*
Y401909D01*
X813709Y401938D01*
G03X813724Y401987I-1524J493D01*
G01X813738Y402038D01*
X813800Y402100D01*
X813761Y402139D01*
X813772Y402235D01*
G03X813782Y402417I-1591J179D01*
G01Y403817D01*
G03X812457Y405395I-1602J0D01*
G01X812395Y405405D01*
X812100Y405700D01*
X811200D01*
X811000Y405900D01*
Y413000D01*
X814966D01*
Y405636D01*
X815100D01*
Y405300D01*
X816000Y404400D01*
Y402000D01*
G37*
G36*
G01X892753Y203940D02*
X891778Y204916D01*
Y205280D01*
X891412D01*
X890102Y206592D01*
Y218002D01*
X891300Y219200D01*
X904000D01*
X905933Y217267D01*
Y199228D01*
X904369Y197664D01*
X893822D01*
X892753Y198733D01*
Y203940D01*
G37*
G36*
G01X876236Y198599D02*
X872950Y201885D01*
Y218050D01*
X873800Y218900D01*
X888100D01*
X888900Y218100D01*
Y205828D01*
X890942Y203786D01*
Y199267D01*
X890274Y198599D01*
X876236D01*
G37*
G36*
G01X887268Y267458D02*
X886404Y268322D01*
Y314101D01*
X886351Y314153D01*
Y315197D01*
X889346Y318192D01*
X901630D01*
X904736Y315086D01*
Y270869D01*
X901325Y267458D01*
X887268D01*
G37*
G36*
G01X898000Y220500D02*
X875000D01*
X873900Y221600D01*
Y238600D01*
X876900Y241600D01*
X898800D01*
X900800Y239600D01*
Y223300D01*
X898000Y220500D01*
G37*
G36*
G01X880333Y394582D02*
X872682D01*
X870558Y396706D01*
X864201D01*
X863707Y397200D01*
Y409418D01*
X865377Y411088D01*
X878177D01*
X879353Y412264D01*
X903589D01*
X905062Y410791D01*
Y403172D01*
X904721Y402831D01*
X881587D01*
X880753Y401997D01*
Y395002D01*
X880333Y394582D01*
G37*
G36*
G01X903317Y367128D02*
X891987D01*
X878588Y380527D01*
Y388067D01*
X876479Y390176D01*
Y393078D01*
X876769Y393368D01*
X880266D01*
X880542Y393092D01*
Y387089D01*
X882390Y385241D01*
X903719D01*
X904526Y384434D01*
Y368337D01*
X903317Y367128D01*
G37*
G36*
G01X882838Y386588D02*
X882072Y387354D01*
Y400326D01*
X883376Y401630D01*
X903470D01*
X904603Y400496D01*
Y388092D01*
X903099Y386588D01*
X882838D01*
G37*
%LPC*%
G75*
G36*
G01X119602Y546503D02*
G03X119402Y546303I0J-200D01*
G02X117203Y548502I-2202J-3D01*
G03X117403Y548702I0J200D01*
G02X119602Y546503I2202J3D01*
G37*
G36*
G01X136250Y536559D02*
G02X134803Y534849I724J-2080D01*
G03X134278Y535294I-394J67D01*
G02X135725Y537004I-724J2080D01*
G03X136250Y536559I394J-67D01*
G37*
G36*
G01X98713Y569586D02*
X99019Y569585D01*
X99819D01*
Y568785D01*
X99019D01*
X98713Y568786D01*
X97913D01*
Y569586D01*
X98713D01*
G37*
G36*
G01X128828Y568338D02*
G03X128173Y568326I-323J-236D01*
G02X128126Y570854I-1826J1230D01*
G03X128781Y570866I323J236D01*
G02X128828Y568338I1826J-1230D01*
G37*
G36*
G01X356839Y86337D02*
G02X355797Y88948I-3296J198D01*
G03X356469Y89253I272J293D01*
G02X356468Y89379I4200J96D01*
G01Y94479D01*
G02X364870I4201J0D01*
G01Y89379D01*
G02X357536Y86579I-4201J0D01*
G03X356839Y86337I-298J-267D01*
G37*
G36*
G01X691734Y512096D02*
X692092Y512062D01*
X692892D01*
Y511262D01*
X692092D01*
X691734Y511296D01*
X690934D01*
Y512096D01*
X691734D01*
G37*
G36*
G01X692892Y518062D02*
Y517262D01*
X692092D01*
X691734Y517296D01*
X690934D01*
Y518096D01*
X691734D01*
X692092Y518062D01*
X692892D01*
G37*
G54D81*
X84500Y679600D03*
G54D79*
X96570Y581730D03*
G54D83*
X339331Y49803D03*
G54D82*
X360669D03*
X339331Y91929D03*
G54D87*
X666432Y492452D03*
X672432D03*
G54D80*
X135350Y601800D03*
G54D85*
X556510Y53626D03*
X556710Y64726D03*
G54D78*
X126337Y554085D03*
X102601Y507300D03*
X58926Y582407D03*
X135012Y510200D03*
X138900Y525999D03*
X133800Y528500D03*
X117400Y567650D03*
X108371Y577258D03*
X200000Y664200D03*
X316465Y716063D03*
X678740Y508760D03*
X777165Y509835D03*
G54D86*
X531050Y46998D03*
G54D84*
X346457Y57007D03*
X353543Y62913D03*
Y55039D03*
X346457Y66850D03*
Y74724D03*
Y84567D03*
X353543Y78661D03*
Y70787D03*
G54D88*
X765354Y510236D03*
G54D89*
X745669D03*
G54D77*
X95913Y563186D03*
X155195Y553466D03*
X68778Y505277D03*
X70978D03*
X79968Y505366D03*
X82168D03*
X63151Y505377D03*
X65351D03*
X74273Y505379D03*
X76473D03*
X85573Y505500D03*
X87773D03*
X91173D03*
X93373D03*
X96800D03*
X99000D03*
X37332Y520171D03*
Y522371D03*
X37375Y525895D03*
Y528095D03*
X37365Y531538D03*
Y533738D03*
X107174Y534124D03*
X37258Y537154D03*
X107174Y537524D03*
X37258Y539354D03*
X37358Y542781D03*
Y544981D03*
X37403Y548408D03*
Y550608D03*
X147140Y553435D03*
X150540D03*
X151795Y553466D03*
X37385Y554053D03*
Y556253D03*
X142337Y556786D03*
X145737D03*
X147140Y556835D03*
X150540D03*
X151795Y556866D03*
X155195D03*
X144867Y558691D03*
X148267D03*
X149557Y558723D03*
X152957D03*
X140187Y558791D03*
X143587D03*
X102576Y559066D03*
X155401Y559767D03*
X37300Y559800D03*
X102576Y561266D03*
X37300Y562000D03*
X101819Y563185D03*
X94070Y563215D03*
X40168Y565616D03*
Y569016D03*
X49656Y572895D03*
X47550Y578550D03*
Y581950D03*
X79447Y567279D03*
X62650Y575200D03*
X59600Y576950D03*
X62650Y578600D03*
X66050D03*
X128600Y505800D03*
X146003Y508289D03*
Y510489D03*
X145500Y516200D03*
X142337Y547786D03*
X145737D03*
X147140Y547835D03*
X150540D03*
X151795Y547866D03*
X152957Y567723D03*
X144867Y567691D03*
X148267D03*
X149557Y567723D03*
X140187Y567791D03*
X143587D03*
X147516Y569105D03*
X101819Y569185D03*
X95913Y569186D03*
X91670Y569215D03*
X94070D03*
X147516Y571505D03*
X95087Y571699D03*
X97487D03*
X104930Y575252D03*
Y577652D03*
X132400Y601800D03*
X138300D03*
X139489Y603037D03*
X142889D03*
X130800Y603800D03*
X125300Y629700D03*
Y631900D03*
Y633800D03*
X123700Y609400D03*
X93500Y675600D03*
Y679000D03*
X90500Y680200D03*
Y682600D03*
X84500Y675600D03*
X87900D03*
X84500Y682600D03*
X211018Y466493D03*
X213218D03*
X199700Y515500D03*
X201300D03*
X204700D03*
X206300D03*
X209700D03*
X211300D03*
X214700D03*
X216300D03*
X219700D03*
X188071Y560910D03*
X195790Y568400D03*
X197990D03*
X182848Y569951D03*
X195530Y570170D03*
X198930D03*
X195530Y573570D03*
X183205Y574091D03*
X193789Y580925D03*
X195330Y581740D03*
X199810Y558690D03*
X202010D03*
X155789Y519712D03*
X170400Y525600D03*
Y527800D03*
X196300Y524500D03*
X199700D03*
X201300D03*
X204700D03*
X206300D03*
X209700D03*
X211300D03*
X214700D03*
X216300D03*
X219700D03*
X171302Y575158D03*
X198930Y579170D03*
X200930Y581740D03*
X179805Y579691D03*
X183205D03*
X184789Y580925D03*
X179805Y583091D03*
X183205D03*
X251500Y628800D03*
X372700Y29900D03*
Y32100D03*
X378900Y602900D03*
X381100D03*
X366220Y604364D03*
X369020D03*
X360400Y604700D03*
X363200D03*
X373900Y605900D03*
X377300D03*
X356000Y611200D03*
Y614000D03*
X374815Y616325D03*
X368080Y621236D03*
X347500Y630400D03*
X350900D03*
X352300D03*
X355700D03*
X378300Y29900D03*
Y32100D03*
X491800Y52000D03*
X495200D03*
X504800D03*
X508200D03*
X510400Y53700D03*
X512600D03*
X497050Y54230D03*
X499250D03*
X491800Y55400D03*
X495200D03*
X504800D03*
X508200D03*
X494750Y34881D03*
X494760Y36783D03*
Y38983D03*
X498318Y41507D03*
X511800Y63900D03*
Y66100D03*
X492400Y68400D03*
X494600D03*
X516790Y76600D03*
Y78800D03*
X666432Y483802D03*
Y485502D03*
Y487902D03*
Y489502D03*
Y495402D03*
X688675Y473636D03*
X691075D03*
X691800Y495309D03*
Y497709D03*
Y499009D03*
Y501409D03*
X695244Y479089D03*
Y481289D03*
X672432Y481402D03*
Y483802D03*
Y485502D03*
Y487902D03*
Y489502D03*
X685800Y495309D03*
X672432Y495402D03*
X685800Y497709D03*
Y499009D03*
Y501409D03*
X781467Y510352D03*
X783867D03*
X785467D03*
X787867D03*
X789467D03*
X791867D03*
X793467D03*
X795867D03*
X685296Y511647D03*
X687696D03*
X694892Y511662D03*
X688934Y511696D03*
X755175Y523896D03*
X757575D03*
X759175D03*
X761575D03*
X764253Y523925D03*
X766653D03*
X768253D03*
X770653D03*
X772253D03*
X774653D03*
X697200Y443200D03*
X697025Y444786D03*
Y447186D03*
X688934Y517696D03*
X694892Y517662D03*
X687696Y517647D03*
X685296D03*
X755175Y529896D03*
X757575D03*
X759175D03*
X761575D03*
X764253Y529925D03*
X766653D03*
X768253D03*
X770653D03*
X772253D03*
X774653D03*
X771294Y539131D03*
X783867Y516352D03*
X785467D03*
X787867D03*
X789467D03*
X791867D03*
X793467D03*
X795867D03*
X882786Y270945D03*
X808025Y425415D03*
X812396Y429421D03*
X818000Y394700D03*
X816534Y394862D03*
X882609Y213965D03*
X888786Y268545D03*
Y270945D03*
X888109Y226065D03*
X882609D03*
X878290Y224273D03*
X874890D03*
X888109Y221565D03*
X882609D03*
%LPD*%
G75*
G54D10*
X61024Y34449D03*
X33464D03*
X56102Y24606D03*
X38386D03*
X108268Y44292D03*
X80708D03*
X103346Y34449D03*
X85630D03*
G54D20*
X49306Y532622D03*
X41865Y532638D03*
X49385Y555153D03*
X41885D03*
X49306Y538249D03*
X41758Y538254D03*
X49306Y543876D03*
X41858Y543881D03*
X49306Y526995D03*
X41875D03*
X49306Y521269D03*
X41832Y521271D03*
X49385Y549526D03*
X41903Y549508D03*
X49385Y560879D03*
X41800Y560900D03*
X58500Y575850D03*
X54156Y571795D03*
X140400Y479700D03*
Y483900D03*
X116172Y497305D03*
X128200Y610500D03*
X129800Y630800D03*
Y634900D03*
Y639000D03*
X200200Y489500D03*
X174900Y530700D03*
X160289Y520812D03*
X187680Y520045D03*
X187238Y536101D03*
X178086Y513171D03*
X150503Y509389D03*
X197100Y528500D03*
X175487Y587147D03*
X188110Y617688D03*
X190104Y636190D03*
X197570Y636210D03*
X151700Y590500D03*
X207000Y642300D03*
X191245Y642681D03*
X199100Y642800D03*
X219700Y471100D03*
X228425Y484151D03*
X252400Y543600D03*
X242920Y562521D03*
X219453Y528088D03*
X225508Y637894D03*
X215200Y634500D03*
X227548Y581666D03*
X238900Y597500D03*
X268700Y588500D03*
X252900Y571100D03*
Y567100D03*
X245130Y571032D03*
X244830Y566732D03*
X296520Y561123D03*
X347600Y574900D03*
X318022Y606283D03*
X307800Y661300D03*
X377200Y31000D03*
X365700Y574900D03*
X360933Y673696D03*
X360800Y665580D03*
X461660Y25990D03*
X493660Y37883D03*
X441400Y37800D03*
X521290Y77700D03*
X699744Y480189D03*
X754979Y538718D03*
X770194Y540231D03*
X762705Y538797D03*
X831439Y340820D03*
X816896Y428321D03*
G54D11*
X66435Y8514D03*
X61435D03*
X56435D03*
X51435D03*
X46435D03*
X41435D03*
X36435D03*
X31435D03*
X26435D03*
X21435D03*
X16435D03*
X8514Y10593D03*
Y15593D03*
Y20593D03*
Y25593D03*
Y30593D03*
Y35593D03*
Y40593D03*
Y45593D03*
Y50593D03*
Y55593D03*
Y60593D03*
Y65593D03*
Y70593D03*
Y75593D03*
Y80593D03*
Y85593D03*
Y90593D03*
Y95593D03*
Y100593D03*
Y105593D03*
Y110593D03*
Y115593D03*
Y120593D03*
Y125593D03*
Y130593D03*
Y135593D03*
Y140593D03*
Y145593D03*
Y150593D03*
Y155593D03*
Y160593D03*
Y165593D03*
Y170593D03*
Y175593D03*
Y180593D03*
Y185593D03*
Y190593D03*
Y195593D03*
Y200593D03*
Y205593D03*
Y210593D03*
Y215593D03*
Y220593D03*
Y225593D03*
Y230593D03*
Y235593D03*
Y240593D03*
Y245593D03*
Y250593D03*
Y255593D03*
Y260593D03*
Y265593D03*
Y270593D03*
Y275593D03*
Y280593D03*
Y285593D03*
Y290593D03*
Y295593D03*
Y300593D03*
Y305593D03*
Y310593D03*
Y315593D03*
Y320593D03*
Y325593D03*
Y330593D03*
Y335593D03*
Y340593D03*
Y345593D03*
Y350593D03*
Y355593D03*
Y360593D03*
Y365593D03*
Y370593D03*
Y375593D03*
Y380593D03*
Y385593D03*
Y390593D03*
Y395593D03*
Y400593D03*
Y405593D03*
Y410593D03*
Y415593D03*
Y420593D03*
Y425593D03*
Y430593D03*
Y435593D03*
Y440593D03*
Y445593D03*
Y450593D03*
Y455593D03*
Y460593D03*
Y465593D03*
Y470593D03*
Y475593D03*
Y480593D03*
Y485593D03*
Y490593D03*
Y495593D03*
Y500593D03*
Y505593D03*
Y510593D03*
Y515593D03*
Y520593D03*
Y525593D03*
Y530593D03*
Y535593D03*
Y540593D03*
Y545593D03*
Y550593D03*
Y555593D03*
Y560593D03*
Y565593D03*
Y570593D03*
Y575593D03*
Y580593D03*
Y585593D03*
Y590593D03*
Y595593D03*
Y600593D03*
Y605593D03*
Y610593D03*
Y615593D03*
Y620593D03*
Y625593D03*
Y630593D03*
Y635593D03*
Y640593D03*
Y645593D03*
Y650593D03*
Y655593D03*
Y660593D03*
Y665593D03*
Y670593D03*
Y675593D03*
Y680593D03*
Y685593D03*
Y690593D03*
Y695593D03*
Y700593D03*
Y705593D03*
Y710593D03*
Y715593D03*
Y720593D03*
X9942Y725256D03*
X12178Y729728D03*
X14414Y734200D03*
X16650Y738672D03*
X18886Y743144D03*
X21122Y747617D03*
X23358Y752089D03*
X111683Y63266D03*
Y58266D03*
Y23266D03*
Y18266D03*
Y13266D03*
X111435Y8514D03*
X106435D03*
X101435D03*
X96435D03*
X91435D03*
X86435D03*
X81435D03*
X76435D03*
X71435D03*
X111683Y118266D03*
Y113266D03*
Y108266D03*
Y103266D03*
Y98266D03*
Y93266D03*
Y88266D03*
Y83266D03*
Y78266D03*
Y73266D03*
Y68266D03*
Y203266D03*
Y198266D03*
Y193266D03*
Y188266D03*
Y183266D03*
Y178266D03*
Y173266D03*
Y168266D03*
Y163266D03*
Y158266D03*
Y153266D03*
Y148266D03*
Y278266D03*
Y273266D03*
Y268266D03*
Y263266D03*
Y258266D03*
Y253266D03*
Y248266D03*
Y243266D03*
Y238266D03*
Y233266D03*
Y228266D03*
Y223266D03*
Y218266D03*
Y213266D03*
Y208266D03*
Y348266D03*
Y343266D03*
Y338266D03*
Y333266D03*
Y328266D03*
Y323266D03*
Y318266D03*
Y313266D03*
Y308266D03*
Y303266D03*
Y298266D03*
Y293266D03*
Y288266D03*
Y283266D03*
Y418266D03*
Y413266D03*
Y408266D03*
Y403266D03*
Y398266D03*
Y393266D03*
Y388266D03*
Y383266D03*
Y378266D03*
Y373266D03*
Y368266D03*
Y363266D03*
Y358266D03*
Y353266D03*
X103940Y635460D03*
X76118Y625275D03*
X81118D03*
X86300Y703200D03*
X99337Y683756D03*
Y678756D03*
Y673756D03*
X86300Y708000D03*
X95200Y667500D03*
X90400D03*
X85600D03*
X76549Y680547D03*
Y675547D03*
X81549Y680547D03*
Y675547D03*
X134223Y691027D03*
X122335Y660582D03*
Y655782D03*
X76395Y755266D03*
X81395D03*
X86395D03*
X91395D03*
X96395D03*
X101395D03*
X106395D03*
X111395D03*
X116395D03*
X121395D03*
X126395D03*
X131395D03*
X136395D03*
X141395D03*
X108928Y744775D03*
X113928D03*
X118928D03*
X123928D03*
X103928D03*
X98928D03*
X93928D03*
X83125Y719240D03*
Y724040D03*
X184800Y484556D03*
X171780Y496031D03*
X197400Y549000D03*
X170597Y539852D03*
X175200Y555000D03*
X184700Y552000D03*
X160157Y537164D03*
X149824Y542794D03*
X202380Y567970D03*
X169021Y610228D03*
X157800Y602900D03*
X154903Y608458D03*
X169242Y603107D03*
X163991Y606162D03*
X207820Y570860D03*
X206900Y577100D03*
X179500Y602800D03*
X186800Y595600D03*
X197264Y596849D03*
X196700Y704985D03*
X201700D03*
X206700D03*
X211700D03*
X191700D03*
X146395Y755266D03*
X151395D03*
X156395D03*
X161395D03*
X166395D03*
X171395D03*
X176395D03*
X181395D03*
X186395D03*
X191395D03*
X196395D03*
X201395D03*
X206395D03*
X211395D03*
X155400Y717700D03*
X224300Y552500D03*
X220500Y557800D03*
X221700Y545500D03*
X219700Y563100D03*
X236074Y536841D03*
X236260Y529177D03*
X257600Y543400D03*
X213201Y570843D03*
X219375Y581711D03*
X219638Y576359D03*
X219688Y587096D03*
X223292Y567000D03*
X219000Y617500D03*
X221700Y704985D03*
X226700D03*
X216700D03*
X216395Y755266D03*
X221395D03*
X226395D03*
X231395D03*
X236395D03*
X241395D03*
X246395D03*
X251395D03*
X256395D03*
X261395D03*
X266395D03*
X271395D03*
X276395D03*
X281395D03*
X249200Y733700D03*
Y728700D03*
Y723700D03*
Y718700D03*
Y738500D03*
X330546Y8514D03*
X325546D03*
X320546D03*
X315546D03*
X310546D03*
X305546D03*
X300546D03*
X296034Y9002D03*
Y14002D03*
Y19002D03*
Y24002D03*
Y29002D03*
Y34002D03*
Y39002D03*
Y44002D03*
Y49002D03*
Y54002D03*
Y59002D03*
Y64002D03*
Y69002D03*
Y74002D03*
Y79002D03*
Y84002D03*
Y89002D03*
Y94002D03*
Y99002D03*
Y104002D03*
Y109002D03*
Y114002D03*
Y119002D03*
Y124002D03*
Y129002D03*
Y134002D03*
Y139002D03*
X334782Y184928D03*
X321182Y202574D03*
Y197774D03*
X305882Y195474D03*
X305382Y190174D03*
X334882Y195478D03*
Y200478D03*
Y190478D03*
X335061Y222578D03*
X335100Y218378D03*
X323492Y214234D03*
X305862Y210014D03*
X335000Y621200D03*
Y615400D03*
Y610200D03*
X325600Y640100D03*
X330400D03*
X335200D03*
X322000Y653081D03*
X312400D03*
X317200D03*
X307600D03*
X298700Y674600D03*
X303700D03*
X286395Y755266D03*
X291395D03*
X296395D03*
X301395D03*
X306395D03*
X311395D03*
X316395D03*
X321395D03*
X326395D03*
X331395D03*
X336395D03*
X315520Y711720D03*
X320320D03*
X325120D03*
X305559Y720973D03*
X310559D03*
X305559Y725973D03*
X310559D03*
X299500Y725400D03*
X373073Y201889D03*
X378965Y610613D03*
X361792Y625652D03*
X399754Y706071D03*
X389168Y743572D03*
X391404Y739100D03*
X393640Y734628D03*
X395876Y730156D03*
X398112Y725684D03*
X399754Y716071D03*
Y711071D03*
X435000Y29000D03*
X438500Y25500D03*
Y32500D03*
X491500Y71600D03*
X496500D03*
X491500Y76600D03*
X496500D03*
X556510Y53626D03*
X516693Y46345D03*
X521493D03*
X516693Y41545D03*
X521493D03*
Y36745D03*
X516693D03*
X521493Y31945D03*
X526530Y43775D03*
X516693Y31945D03*
X567700Y28240D03*
X548550Y76480D03*
X525000Y76300D03*
X525200Y80900D03*
X556710Y64726D03*
X543750Y76480D03*
X506500Y76600D03*
X501500D03*
Y71600D03*
X608847Y34607D03*
X614032Y33307D03*
X621747Y63307D03*
X626647Y77507D03*
Y72507D03*
Y67507D03*
X593017Y69796D03*
X588217Y74596D03*
Y69796D03*
X576624Y193205D03*
Y198205D03*
Y203205D03*
Y208205D03*
Y213205D03*
Y223205D03*
Y228205D03*
Y233205D03*
Y238205D03*
Y243205D03*
Y248205D03*
Y253205D03*
Y258205D03*
Y263205D03*
Y268205D03*
Y273205D03*
Y278205D03*
Y333205D03*
Y338205D03*
Y343205D03*
Y348205D03*
Y353205D03*
Y358205D03*
Y363205D03*
Y368205D03*
Y373205D03*
Y378205D03*
Y383205D03*
Y388205D03*
Y393205D03*
Y398205D03*
Y403205D03*
Y408205D03*
Y413205D03*
Y418205D03*
Y423205D03*
Y428205D03*
Y433205D03*
Y438205D03*
Y443205D03*
Y448205D03*
Y498205D03*
Y503205D03*
Y508205D03*
Y513205D03*
Y518205D03*
Y523205D03*
Y528205D03*
Y533205D03*
Y538205D03*
Y543205D03*
Y548205D03*
Y553205D03*
Y558205D03*
Y563205D03*
Y568205D03*
Y573205D03*
Y578205D03*
Y583205D03*
Y588205D03*
X578710Y592712D03*
X580946Y597184D03*
X583182Y601656D03*
X585418Y606129D03*
X587654Y610601D03*
X635975Y621407D03*
X640975D03*
X715546Y8514D03*
X710546D03*
X705546D03*
X700546D03*
X695546D03*
X668847Y27107D03*
X663847D03*
X658847D03*
X653847D03*
X653601Y46761D03*
X658601D03*
X653601Y51761D03*
X658601D03*
X663601Y46761D03*
Y51761D03*
X668601Y46761D03*
Y51761D03*
X700065Y135985D03*
Y125985D03*
Y115985D03*
X710065D03*
Y125985D03*
Y135985D03*
X649590Y114036D03*
X700065Y155985D03*
X710065D03*
Y145985D03*
X696159Y225829D03*
X698909Y278104D03*
X700065Y265985D03*
Y255985D03*
Y245985D03*
Y235985D03*
X710065D03*
Y245985D03*
Y255985D03*
Y265985D03*
X709625Y275991D03*
X710065Y325985D03*
Y315985D03*
X711574Y285985D03*
X708307Y295429D03*
X710065Y305985D03*
Y335985D03*
Y345985D03*
X700065Y385985D03*
Y395985D03*
Y405985D03*
Y415985D03*
X710065Y375985D03*
Y355985D03*
Y365985D03*
Y455985D03*
X684399Y466984D03*
Y471984D03*
X663500Y484000D03*
Y489000D03*
Y494000D03*
X692282Y476720D03*
X689875Y464586D03*
X698275Y438305D03*
X683100Y485200D03*
X679832Y494100D03*
Y489100D03*
X679100Y483300D03*
X674900D03*
X674832Y489100D03*
Y494100D03*
X682800Y480700D03*
X693392Y520482D03*
X683392D03*
X688392D03*
X705080Y521247D03*
X694272Y495786D03*
X645975Y621407D03*
X650975D03*
X655975D03*
X660975D03*
X665975D03*
X670975D03*
X675975D03*
X680975D03*
X685975D03*
X690975D03*
X695975D03*
X700975D03*
X705975D03*
X710975D03*
X715975D03*
X785546Y8514D03*
X780546D03*
X775546D03*
X770546D03*
X765546D03*
X760546D03*
X755546D03*
X750546D03*
X745546D03*
X740546D03*
X735546D03*
X730546D03*
X725546D03*
X720546D03*
X770065Y55985D03*
Y65985D03*
Y75985D03*
X750065Y85985D03*
X770065D03*
X760065D03*
X740065D03*
X730065Y95985D03*
X760065D03*
X780065D03*
X770065D03*
Y105985D03*
X780065D03*
Y115985D03*
X730065Y135985D03*
Y125985D03*
Y115985D03*
Y105985D03*
X750065Y95985D03*
X740065D03*
X750065Y105985D03*
X760065D03*
X740065D03*
X750065Y115985D03*
X760065D03*
X770065D03*
X740065D03*
X750065Y125985D03*
X760065D03*
X770065D03*
X780065D03*
X740065D03*
X750065Y135985D03*
X760065D03*
X770065D03*
X780065D03*
X740065D03*
X720065Y105985D03*
Y115985D03*
Y125985D03*
Y135985D03*
Y155985D03*
X780065D03*
X730065D03*
Y145985D03*
X750065D03*
X760065D03*
X770065D03*
X780065D03*
X740065D03*
X750065Y155985D03*
X760065D03*
X770065D03*
X740065D03*
X750065Y165985D03*
X760065D03*
X770065D03*
X740065D03*
X750065Y175985D03*
X760065D03*
X770065D03*
X740065D03*
X750065Y185985D03*
X760065D03*
X770065D03*
X740065D03*
X750065Y195985D03*
X760065D03*
X770065D03*
X740065D03*
X750065Y205985D03*
X760065D03*
X770065D03*
X740065D03*
X720065Y145985D03*
X730065Y215985D03*
X773469Y277001D03*
X780065Y275985D03*
X787817Y275879D03*
X750065Y215985D03*
X760065D03*
X770065D03*
X780065D03*
X740065D03*
X780065Y265985D03*
Y255985D03*
Y245985D03*
Y235985D03*
Y225985D03*
X770065Y265985D03*
Y255985D03*
Y245985D03*
Y235985D03*
Y225985D03*
X763133Y275881D03*
X759790Y263326D03*
X760065Y255985D03*
Y245985D03*
Y235985D03*
Y225985D03*
X750065Y275985D03*
Y265985D03*
Y255985D03*
Y245985D03*
Y235985D03*
Y225985D03*
X741608Y277171D03*
X740065Y265985D03*
Y255985D03*
Y245985D03*
Y235985D03*
Y225985D03*
X730830Y276087D03*
X730065Y265985D03*
Y255985D03*
X731766Y246017D03*
X730065Y235985D03*
X730190Y223549D03*
X720237Y223228D03*
X720065Y235985D03*
X721766Y246017D03*
X720065Y255985D03*
Y265985D03*
X718617Y275736D03*
X770065Y335985D03*
X760065D03*
X720065Y325985D03*
X760065D03*
X750065D03*
X740065D03*
X730065D03*
X720065Y315985D03*
X780065Y285985D03*
X770065D03*
X760065D03*
X750065Y295985D03*
X760065D03*
X770065D03*
X780065D03*
Y305985D03*
Y315985D03*
Y325985D03*
Y335985D03*
Y345985D03*
X770065Y305985D03*
Y315985D03*
Y325985D03*
Y345985D03*
X760065Y305985D03*
Y315985D03*
Y345985D03*
X750065Y305985D03*
Y315985D03*
Y335985D03*
Y345985D03*
X740065Y305985D03*
Y315985D03*
Y335985D03*
Y345985D03*
X730065D03*
Y335985D03*
Y315985D03*
X752500Y286000D03*
X740065Y295985D03*
X741000Y286000D03*
X730065Y305985D03*
X729486Y296094D03*
X729294Y285987D03*
X721574Y285985D03*
X719049Y296011D03*
X720065Y305985D03*
Y335985D03*
Y345985D03*
X750065Y415985D03*
X760065D03*
X770065D03*
X780065D03*
X730065D03*
X740065D03*
X750065Y405985D03*
X760065D03*
X770065D03*
X780065D03*
X730065D03*
X740065D03*
X780065Y395985D03*
X770065D03*
X760065D03*
X750065D03*
X740065D03*
X730065D03*
X720065Y375985D03*
X730065Y365985D03*
Y375985D03*
Y385985D03*
X750065D03*
X760065D03*
X770065D03*
X780065D03*
X740065D03*
X750065Y375985D03*
X760065D03*
X770065D03*
X780065D03*
X740065D03*
X750065Y365985D03*
X760065D03*
X770065D03*
X780065D03*
X740065D03*
X780065Y355985D03*
X770065D03*
X760065D03*
X750065D03*
X740065D03*
X730065D03*
X720065D03*
Y365985D03*
Y455985D03*
Y465985D03*
X750065D03*
X760065D03*
X770065D03*
X780065D03*
X730065D03*
X740065D03*
X780065Y455985D03*
X770065D03*
X760065D03*
X750065D03*
X740065D03*
X730065D03*
X750065Y445985D03*
X760065D03*
X770065D03*
X780065D03*
X730065D03*
X740065D03*
X750065Y435985D03*
X760065D03*
X770065D03*
X780065D03*
X740065D03*
X750065Y425985D03*
X760065D03*
X770065D03*
X780065D03*
X736217Y493664D03*
X776658Y489380D03*
X771658D03*
X781658D03*
Y494380D03*
X741217Y493664D03*
X776658Y494380D03*
X771658D03*
X784604Y519082D03*
X758512Y534430D03*
X747107Y536580D03*
X739334Y524156D03*
X752602Y517850D03*
X736580Y507734D03*
X788015Y507785D03*
X783015D03*
X747602Y517850D03*
X731580Y507734D03*
X716578Y509762D03*
X721590Y511659D03*
X726590D03*
X720975Y621407D03*
X725975D03*
X730975D03*
X735975D03*
X740975D03*
X745975D03*
X750975D03*
X755975D03*
X760975D03*
X765975D03*
X770975D03*
X775975D03*
X780975D03*
X785975D03*
X850546Y8514D03*
X845546D03*
X840546D03*
X835546D03*
X830546D03*
X825546D03*
X820546D03*
X815546D03*
X810546D03*
X805546D03*
X800546D03*
X795546D03*
X790546D03*
X820065Y105985D03*
Y135985D03*
Y125985D03*
Y115985D03*
X810065Y135985D03*
Y125985D03*
Y115985D03*
X790065Y105985D03*
X800065Y115985D03*
X790065D03*
Y125985D03*
X800065D03*
Y135985D03*
X790065D03*
X853436Y108917D03*
Y113717D03*
X853435Y90260D03*
Y95060D03*
X820065Y155985D03*
X810065D03*
X800065D03*
X790065D03*
X820065Y145985D03*
X810065D03*
X790065D03*
X800065D03*
X820313Y276188D03*
X810065Y275985D03*
X800065D03*
X820065Y265985D03*
Y255985D03*
Y245985D03*
Y235985D03*
Y225985D03*
X810065Y265985D03*
Y255985D03*
Y245985D03*
Y235985D03*
X800065Y265985D03*
Y255985D03*
Y245985D03*
Y235985D03*
X790065Y265985D03*
Y255985D03*
Y245985D03*
Y235985D03*
Y225985D03*
X857965Y273150D03*
X820065Y305985D03*
Y295985D03*
Y285985D03*
X810065Y295985D03*
Y285985D03*
X800065D03*
X790065D03*
Y295985D03*
X800065D03*
X810065Y305985D03*
X810000Y314000D03*
X810065Y325985D03*
X800065Y305985D03*
Y315985D03*
Y325985D03*
Y335985D03*
Y345985D03*
X790065Y305985D03*
Y315985D03*
Y325985D03*
X791500Y336000D03*
X790065Y345985D03*
X859407Y300314D03*
Y309914D03*
Y305114D03*
Y295314D03*
Y290314D03*
Y285314D03*
X790065Y415985D03*
Y405985D03*
Y395985D03*
Y375985D03*
X800065D03*
X790065Y365985D03*
X800065D03*
Y355985D03*
X790065D03*
X800065Y455985D03*
Y465985D03*
X790065D03*
Y455985D03*
Y445985D03*
Y435985D03*
X790191Y426486D03*
X809000Y429400D03*
X840057Y494320D03*
X835057D03*
X805771Y518743D03*
X789604Y519082D03*
X794604D03*
X836023Y508124D03*
X825161Y507954D03*
X820161D03*
X815161D03*
X805983Y508293D03*
X793015Y507785D03*
X790975Y621407D03*
X795975D03*
X800975D03*
X805975D03*
X810975D03*
X815975D03*
X820975D03*
X825975D03*
X830975D03*
X835975D03*
X840975D03*
X854971Y637313D03*
Y642313D03*
Y647313D03*
Y652313D03*
Y657313D03*
Y662313D03*
Y667313D03*
Y672313D03*
Y677313D03*
Y682313D03*
Y687313D03*
Y692313D03*
Y697313D03*
Y702313D03*
Y707313D03*
Y712313D03*
X916683Y62377D03*
Y57377D03*
Y52377D03*
Y47377D03*
Y42377D03*
Y37377D03*
Y32377D03*
Y27377D03*
Y22377D03*
Y17377D03*
X915546Y8514D03*
X910546D03*
X905546D03*
X900546D03*
X883222Y59214D03*
X888022D03*
X892822D03*
X897622D03*
X880922Y63714D03*
X885722D03*
X890522D03*
X895322D03*
X900122D03*
X916683Y132377D03*
Y127377D03*
Y122377D03*
Y117377D03*
Y112377D03*
Y107377D03*
Y102377D03*
Y97377D03*
Y92377D03*
Y87377D03*
Y82377D03*
Y77377D03*
Y72377D03*
Y67377D03*
X897250Y81510D03*
X902050D03*
Y86310D03*
X897250D03*
Y91110D03*
X902050D03*
X897250Y95910D03*
X902050D03*
X916683Y207377D03*
Y202377D03*
Y197377D03*
Y192377D03*
Y187377D03*
Y182377D03*
Y177377D03*
Y172377D03*
Y167377D03*
Y162377D03*
Y157377D03*
Y152377D03*
Y147377D03*
Y142377D03*
Y137377D03*
X900600Y201239D03*
X897803Y207684D03*
X902803D03*
X880222Y206781D03*
X875222D03*
X916683Y277377D03*
Y272377D03*
Y267377D03*
Y262377D03*
Y257377D03*
Y252377D03*
Y247377D03*
Y242377D03*
Y237377D03*
Y232377D03*
Y227377D03*
Y222377D03*
Y217377D03*
Y212377D03*
X897195Y275688D03*
X902195D03*
Y270688D03*
X897195D03*
X897803Y217684D03*
Y212684D03*
X902803Y217684D03*
Y212684D03*
X896031Y228468D03*
Y223468D03*
X891031D03*
Y228468D03*
Y238468D03*
X896031D03*
X891031Y233468D03*
X896031D03*
X868376Y271313D03*
X873376D03*
X880122Y216781D03*
X875122D03*
X880222Y211781D03*
X875222D03*
X916683Y347377D03*
Y342377D03*
Y337377D03*
Y332377D03*
Y327377D03*
Y322377D03*
Y317377D03*
Y312377D03*
Y307377D03*
Y302377D03*
Y297377D03*
Y292377D03*
Y287377D03*
Y282377D03*
X896030Y296330D03*
X901030D03*
X900995Y290712D03*
X895995D03*
X900819Y316367D03*
X895819D03*
X900716Y311058D03*
X895716D03*
X864207Y300314D03*
Y309914D03*
Y305114D03*
Y295314D03*
Y290314D03*
Y285314D03*
X916683Y422377D03*
Y417377D03*
Y412377D03*
Y407377D03*
Y402377D03*
Y397377D03*
Y392377D03*
Y387377D03*
Y382377D03*
Y377377D03*
Y372377D03*
Y367377D03*
Y362377D03*
Y357377D03*
Y352377D03*
X876451Y407949D03*
X880665Y410841D03*
X885665D03*
X890665D03*
X895665D03*
X900665D03*
X902091Y369397D03*
X897091D03*
X902091Y374397D03*
X897091D03*
Y379397D03*
X902091D03*
X888548Y392923D03*
X883548D03*
X893548D03*
X888548Y387923D03*
X893548D03*
X883548D03*
X916683Y492377D03*
Y487377D03*
Y482377D03*
Y477377D03*
Y472377D03*
Y467377D03*
Y462377D03*
Y457377D03*
Y452377D03*
Y447377D03*
Y442377D03*
Y437377D03*
Y432377D03*
Y427377D03*
Y562377D03*
Y557377D03*
Y552377D03*
Y547377D03*
Y542377D03*
Y537377D03*
Y532377D03*
Y527377D03*
Y522377D03*
Y517377D03*
Y512377D03*
Y507377D03*
Y502377D03*
Y497377D03*
Y637377D03*
Y632377D03*
Y627377D03*
Y622377D03*
Y617377D03*
Y612377D03*
Y607377D03*
Y602377D03*
Y597377D03*
Y592377D03*
Y587377D03*
Y582377D03*
Y577377D03*
Y572377D03*
Y567377D03*
Y707377D03*
Y702377D03*
Y697377D03*
Y692377D03*
Y687377D03*
Y682377D03*
Y677377D03*
Y672377D03*
Y667377D03*
Y662377D03*
Y657377D03*
Y652377D03*
Y647377D03*
Y642377D03*
X901041Y753684D03*
X903277Y749212D03*
X905513Y744740D03*
X907749Y740268D03*
X909985Y735796D03*
X912221Y731323D03*
X914457Y726851D03*
X916683Y722377D03*
Y717377D03*
Y712377D03*
G54D21*
X45906Y532622D03*
X38465Y532638D03*
X45985Y555153D03*
X38485D03*
X45906Y538249D03*
X38358Y538254D03*
X45906Y543876D03*
X38458Y543881D03*
X45906Y526995D03*
X38475D03*
X45906Y521269D03*
X38432Y521271D03*
X45985Y549526D03*
X38503Y549508D03*
X45985Y560879D03*
X38400Y560900D03*
X55100Y575850D03*
X50756Y571795D03*
X137000Y479700D03*
Y483900D03*
X112772Y497305D03*
X124800Y610500D03*
X126400Y630800D03*
Y634900D03*
Y639000D03*
X196800Y489500D03*
X171500Y530700D03*
X156889Y520812D03*
X184280Y520045D03*
X183838Y536101D03*
X174686Y513171D03*
X147103Y509389D03*
X193700Y528500D03*
X211800Y634500D03*
X172087Y587147D03*
X184710Y617688D03*
X186704Y636190D03*
X194170Y636210D03*
X148300Y590500D03*
X203600Y642300D03*
X187845Y642681D03*
X195700Y642800D03*
X216300Y471100D03*
X225025Y484151D03*
X249000Y543600D03*
X239520Y562521D03*
X216053Y528088D03*
X222108Y637894D03*
X224148Y581666D03*
X235500Y597500D03*
X265300Y588500D03*
X249500Y571100D03*
Y567100D03*
X241730Y571032D03*
X241430Y566732D03*
X293120Y561123D03*
X344200Y574900D03*
X314622Y606283D03*
X304400Y661300D03*
X373800Y31000D03*
X362300Y574900D03*
X357533Y673696D03*
X357400Y665580D03*
X458260Y25990D03*
X490260Y37883D03*
X438000Y37800D03*
X517890Y77700D03*
X696344Y480189D03*
X751579Y538718D03*
X766794Y540231D03*
X759305Y538797D03*
X828039Y340820D03*
X813496Y428321D03*
G54D30*
X123800Y504600D03*
X148716Y570305D03*
X171979Y583387D03*
X203900Y634400D03*
X251200Y609800D03*
X284736Y598419D03*
X355889Y540188D03*
X365809Y509699D03*
X362180Y551390D03*
X667632Y486702D03*
Y490702D03*
Y494202D03*
Y482602D03*
G54D12*
G01X-36569Y-23804D02*
Y-103804D01*
G01D02*
X1258031D01*
G01X-40569Y-7804D02*
G02I-12000J0D01*
G01X-45719D02*
G02I-6850J0D01*
G01X-52569Y-23804D02*
Y8196D01*
G01X-36569Y-23804D02*
X1258031D01*
G01X-36569Y-59304D02*
X1258031D01*
G01X-36569Y-7804D02*
X-68569D01*
G01X65400Y549550D02*
X63219D01*
X62276Y550493D01*
G01X65400Y546050D02*
X61750D01*
X61100Y546700D01*
G01X64151Y517527D02*
Y521695D01*
G01X49356Y521269D02*
X53524D01*
G01X49356Y526995D02*
X53524D01*
G01X49356Y532622D02*
X53524D01*
G01X49356Y538249D02*
X52606D01*
X52613Y538242D01*
G01X49356Y543876D02*
X52408D01*
G01X49435Y549526D02*
X52603D01*
G01X49435Y555153D02*
X52485D01*
G01X49435Y560879D02*
X53300D01*
G01X64350Y582700D02*
X67239D01*
X67852Y583313D01*
G01X112722Y493971D02*
Y497305D01*
G01X123850Y504600D02*
X120500D01*
G01X120273Y500809D02*
Y504373D01*
X120500Y504600D01*
G01X78474Y558398D02*
Y562302D01*
X78247Y562529D01*
G01X78475Y554363D02*
Y558397D01*
X78474Y558398D01*
G01X94720Y557158D02*
X96638Y555240D01*
X97994D01*
G01X92286Y517527D02*
Y521695D01*
G01X86659Y517527D02*
Y521695D01*
G01X81032Y517527D02*
Y521695D01*
G01X75405Y517527D02*
Y521695D01*
G01X69778Y517527D02*
Y521695D01*
G01X97913Y517527D02*
Y521695D01*
G01X99674Y535824D02*
X98071D01*
X96371Y534124D01*
G01X141189Y595537D02*
Y587465D01*
X144454Y584200D01*
X146750D01*
G01X96287Y576449D02*
X100177D01*
X100180Y576452D01*
G01X93048Y577014D02*
X93613Y576449D01*
X96287D01*
G01X139750Y620200D02*
X136693D01*
X135706Y621187D01*
G01D02*
X133693Y623200D01*
X127950D01*
X126150Y625000D01*
Y626300D01*
G01X137100Y597050D02*
X133600D01*
G01D02*
X129850D01*
X129100Y596300D01*
G01X137100Y589427D02*
Y597050D01*
G01X154650Y572940D02*
X153198D01*
X151061Y575077D01*
Y580279D01*
X149540Y581800D01*
X140850D01*
X137100Y585550D01*
Y589427D01*
G01X129100Y596300D02*
X124100D01*
X122600Y594800D01*
G01X81118Y625275D02*
X86375D01*
X90850Y629750D01*
X107550D01*
X113100Y624200D01*
X115160D01*
X115760Y623600D01*
X122600D01*
X127900Y618300D01*
X129860D01*
X130410Y617750D01*
X133600D01*
G01X126350Y639000D02*
X105000D01*
X104850Y639150D01*
G01X239400Y677600D02*
X236800D01*
X236520Y677320D01*
X185554D01*
X172371Y690503D01*
X154556D01*
X152080Y688027D01*
X132980D01*
X130635Y690372D01*
X108098D01*
X101535Y696935D01*
X90399D01*
X88115Y699219D01*
X83608D01*
X81928Y697539D01*
G01X89560Y712200D02*
X85900D01*
X83125Y714975D01*
Y719240D01*
G01X96700Y712200D02*
X89560D01*
G01X166761Y492270D02*
X170870D01*
G01X196100Y482200D02*
X196900Y483000D01*
X199350D01*
G01X148000Y472050D02*
Y469000D01*
G01X143700Y472050D02*
Y469000D01*
G01X162700Y492250D02*
Y490366D01*
X164765Y488301D01*
X167821D01*
G01X212165Y486458D02*
Y489045D01*
X211324Y489886D01*
G01X218500Y487250D02*
X215950D01*
X215158Y486458D01*
X212165D01*
G01X179000Y503050D02*
Y499800D01*
G01X183788Y536101D02*
Y538513D01*
X184645Y539370D01*
G01X211378Y532351D02*
X208700Y529673D01*
Y529100D01*
G01X191694Y532578D02*
X189678D01*
X188600Y531500D01*
G01X207600Y499130D02*
Y502312D01*
X207500Y502412D01*
G01X187500Y523700D02*
X187730Y523470D01*
Y520045D01*
G01X215448Y532151D02*
X215308D01*
X212300Y529143D01*
Y529000D01*
G01X216003Y528088D02*
X213212D01*
X212300Y529000D01*
G01X174900Y503050D02*
Y499800D01*
G01X212500Y611950D02*
X212923Y612373D01*
Y615000D01*
G01X203950Y638200D02*
X202563D01*
X200963Y636600D01*
G01X203950Y634400D02*
X203163D01*
X200963Y636600D01*
G01X204050Y608800D02*
X203605Y608355D01*
Y605821D01*
G01X156299Y586614D02*
X155003Y587910D01*
X149970D01*
X148250Y589630D01*
Y590500D01*
G01X181497Y589764D02*
X181836D01*
X184050Y587550D01*
X184700D01*
G01X184400Y611350D02*
Y613600D01*
X185100Y614300D01*
G01X188431Y613388D02*
X187519Y614300D01*
X185100D01*
G01X179484Y619120D02*
Y615516D01*
X179700Y615300D01*
G01X151050Y620200D02*
Y616150D01*
X151800Y615400D01*
G01X175348Y568251D02*
X172581D01*
X172047Y567717D01*
G01X199150Y642800D02*
Y640150D01*
X198700Y639700D01*
G01X191295Y642681D02*
Y641805D01*
X193400Y639700D01*
G01X150849Y710215D02*
X149700Y711364D01*
Y715400D01*
G01X160964Y717268D02*
X155832D01*
X155400Y717700D01*
G01X160964Y723268D02*
X155860D01*
X155846Y723282D01*
G01X149700Y723000D02*
X155564D01*
X155846Y723282D01*
G01X213900Y474650D02*
X214400Y475150D01*
X222100D01*
G01X219750Y467300D02*
Y471100D01*
G01D02*
X222100Y473450D01*
Y475150D01*
G01X218500Y487250D02*
Y483677D01*
X217908Y483085D01*
G01X234648Y540453D02*
X235360Y539741D01*
X241108D01*
X244649Y536200D01*
X247550D01*
G01X251346Y554100D02*
Y556100D01*
X248928Y558518D01*
X246980D01*
G01X252950Y567100D02*
X256068Y563982D01*
X256816D01*
G01X259311Y548308D02*
X262547D01*
X262996Y548757D01*
G01X231450Y567000D02*
Y563000D01*
G01X237300Y543650D02*
X241300D01*
X241350Y543700D01*
G01D02*
Y547250D01*
X242700Y548600D01*
G01X252450Y543600D02*
Y539650D01*
X252400Y539600D01*
G01X263400Y531500D02*
X262950D01*
X258650Y535800D01*
G01X273809Y560361D02*
Y558784D01*
X271715Y556690D01*
G01X250400Y636976D02*
Y635601D01*
X250300Y635501D01*
Y633550D01*
G01X245100Y630000D02*
X248650Y633550D01*
X250300D01*
G01X240274Y629709D02*
Y625526D01*
X241800Y624000D01*
G01X245100Y630000D02*
X244809Y629709D01*
X240274D01*
G01X226450Y593200D02*
X229800D01*
G01X225569Y634188D02*
X227288D01*
X228900Y635800D01*
G01X215250Y634500D02*
X217700D01*
X218800Y635600D01*
G01X225900Y611650D02*
Y615000D01*
G01X224000Y619250D02*
Y617000D01*
X221800Y614800D01*
G01D02*
Y611750D01*
G01X215250Y638400D02*
X216000D01*
X218800Y635600D01*
G01X225558Y637894D02*
X226906D01*
Y637794D01*
X228900Y635800D01*
G01X242100Y582950D02*
X244250D01*
X245400Y581800D01*
G01X245100Y636000D02*
Y639500D01*
G01X261900Y588900D02*
X264850D01*
X265250Y588500D01*
G01X227598Y581666D02*
X230834D01*
X230900Y581600D01*
G01X251250Y609800D02*
X247524D01*
X247088Y610236D01*
G01X284786Y598419D02*
X281500D01*
G01X238950Y593500D02*
X242850Y589600D01*
X246800D01*
G01X227825Y576816D02*
X227841Y576800D01*
X231200D01*
G01X227750Y585900D02*
X230400D01*
X234700Y581600D01*
G01X238100Y582950D02*
X236050D01*
X234700Y581600D01*
G01X252300Y580750D02*
X254150D01*
X255400Y579500D01*
G01X230063Y618667D02*
X230362Y618368D01*
Y612437D01*
X236100Y606699D01*
Y597500D01*
X235450D01*
G01X226450Y597200D02*
X226750Y597500D01*
X235450D01*
G01X231642Y622802D02*
Y620246D01*
X230063Y618667D01*
G01X274100Y591000D02*
X272900Y589800D01*
Y587750D01*
G01X288286Y587305D02*
X283127D01*
X281636Y588796D01*
G01X227450Y571900D02*
X231000D01*
G01X252950Y567100D02*
Y571100D01*
G01X273895Y571402D02*
Y571651D01*
X276376Y574132D01*
G01X263238Y666467D02*
Y662686D01*
X262826Y662274D01*
G01X225542Y642006D02*
Y644703D01*
X226708Y645869D01*
G01X215606Y645300D02*
Y642656D01*
X215150Y642200D01*
G01X685907Y30622D02*
Y23707D01*
X682600Y20400D01*
X679293D01*
X668693Y9800D01*
X356900D01*
X327100Y39600D01*
Y125000D01*
X334782Y132682D01*
Y184928D01*
G01X356267Y49803D02*
X360669D01*
G01X339331Y42851D02*
Y49803D01*
G01D02*
Y56755D01*
G01X334929Y49803D02*
X339331D01*
G01D02*
X343733D01*
G01X356267Y91929D02*
X360669D01*
G01X339331Y86327D02*
Y91929D01*
G01D02*
Y97531D01*
G01X334929Y91929D02*
X339331D01*
G01D02*
X343733D01*
G01X329435Y218084D02*
X325042D01*
X323842Y219284D01*
G01X344506Y392324D02*
X343031D01*
X340606Y389899D01*
G01X331550Y387774D02*
X334626D01*
X336000Y386400D01*
Y384400D01*
G01X336230Y377800D02*
X342150D01*
G01X348997Y491678D02*
X349900Y492581D01*
Y499562D01*
X347840Y501622D01*
Y512270D01*
X342789Y517321D01*
Y522085D01*
X342790Y522086D01*
Y527988D01*
X348215Y533413D01*
Y553897D01*
X353933Y559615D01*
Y573832D01*
X355700Y575599D01*
Y579317D01*
G01X355939Y540188D02*
X354372D01*
X352734Y541826D01*
G01X292200Y542473D02*
Y548564D01*
G01X308700Y511950D02*
X306142D01*
X305300Y512792D01*
Y514250D01*
X305350Y514300D01*
G01X312289Y535181D02*
X308254D01*
X308253Y535182D01*
G01D02*
X305782D01*
X301350Y530750D01*
Y527900D01*
G01X292200Y548564D02*
Y553067D01*
X292011Y553256D01*
G01X293070Y561123D02*
Y557870D01*
X292011Y556811D01*
Y553256D01*
G01X364000Y525500D02*
X363317Y526183D01*
X356564D01*
X354662Y524281D01*
Y522996D01*
G01X302700Y551300D02*
X301706D01*
X300192Y552814D01*
X296680D01*
G01X311900Y514950D02*
X311400Y515450D01*
X308700D01*
G01X311900Y514900D02*
Y514950D01*
G01X297850Y527900D02*
Y524500D01*
G01X331673Y579949D02*
X334923D01*
G01X351547Y645938D02*
X354000Y643485D01*
Y637900D01*
G01X348314Y643853D02*
Y638786D01*
X349200Y637900D01*
G01X344150Y579231D02*
X339269D01*
X338551Y579949D01*
X334923D01*
G01X330800Y602610D02*
X329636Y603774D01*
X327538D01*
G01X353669Y600881D02*
X351200Y603350D01*
Y612600D01*
G01X353669Y600881D02*
X354450Y600100D01*
X361600D01*
X361800Y599900D01*
G01X340920Y575234D02*
X341254Y574900D01*
X344150D01*
G01X327538Y600274D02*
X325762Y598498D01*
Y596900D01*
G01X328173Y579949D02*
X326522Y581600D01*
X324900D01*
G01X288286Y598419D02*
Y587305D01*
G01D02*
X290149D01*
X292410Y589566D01*
X293697D01*
G01X288286Y576270D02*
Y573864D01*
X289070Y573080D01*
G01X314800Y681450D02*
X314850Y681400D01*
X317400D01*
X317450Y681450D01*
X325585D01*
X328356Y678679D01*
G01X304350Y661300D02*
X301400D01*
X297900Y664800D01*
G01X396800Y74800D02*
X403000Y68600D01*
X408240D01*
X426100Y50740D01*
Y21199D01*
X433999Y13300D01*
X667243D01*
X677843Y23900D01*
X680000D01*
G01X360669Y44201D02*
Y49803D01*
G01D02*
Y55405D01*
G01Y49803D02*
X365071D01*
G01X360669Y84977D02*
Y91929D01*
G01D02*
Y98881D01*
G01Y91929D02*
X365071D01*
G01X365859Y509699D02*
Y510859D01*
X368100Y513100D01*
G01X362230Y544200D02*
Y546093D01*
X362801Y546664D01*
Y548097D01*
G01X362230Y551390D02*
Y550679D01*
X362801Y550108D01*
Y548097D01*
G01X372714Y509275D02*
X372290Y509699D01*
X369359D01*
G01X359439Y540188D02*
Y541818D01*
X358120Y543137D01*
Y544154D01*
G01X357000Y586750D02*
Y584500D01*
X358964Y582536D01*
X360930D01*
X360980Y582586D01*
G01X377714Y631280D02*
Y627780D01*
G01X360980Y586936D02*
Y582586D01*
G01X369800Y578050D02*
X371752D01*
X372951Y576851D01*
G01X367620Y599564D02*
Y596554D01*
X367133Y596067D01*
G01X375600Y598400D02*
X374436Y599564D01*
X367620D01*
G01X369480Y626036D02*
Y627536D01*
X371180Y629236D01*
G01X373400Y626050D02*
Y627016D01*
X371180Y629236D01*
G01X362250Y570875D02*
X358975D01*
X357500Y569400D01*
Y566950D01*
G01X362250Y574900D02*
Y570875D01*
G01X470531Y-23804D02*
Y-103804D01*
G01X478429Y25800D02*
Y20430D01*
X478426Y20427D01*
G01X482727Y41870D02*
X482076Y41219D01*
X477343D01*
G01X446403Y31700D02*
X439300D01*
X438500Y32500D01*
G01X460300Y57600D02*
X462304D01*
X463223Y56681D01*
X477004D01*
X491500Y71177D01*
G01D02*
Y71600D01*
G01X518890Y59730D02*
X518275Y60345D01*
Y64390D01*
G01X521330Y85630D02*
X523200D01*
X525200Y83630D01*
Y80900D01*
G01X538456Y65144D02*
Y68742D01*
G01X608031Y-23804D02*
Y-103804D01*
G01X685907Y30622D02*
Y60593D01*
X649590Y96910D01*
Y114036D01*
G01X701775Y445986D02*
X706275D01*
G01X689875Y468886D02*
Y464586D01*
G01X707391Y484208D02*
X704341D01*
G01X693350Y455000D02*
Y441150D01*
X696195Y438305D01*
X698275D01*
G01X723031Y-23804D02*
Y-103804D01*
G01X770244Y540231D02*
Y536466D01*
X770275Y536435D01*
G01X751529Y538718D02*
Y537271D01*
X753800Y535000D01*
G01X820241Y327044D02*
Y331519D01*
X820059Y331701D01*
G01X815016Y348564D02*
X812867D01*
X811490Y349941D01*
G01X831489Y340820D02*
X831583Y340914D01*
X835316D01*
G01D02*
X837816Y343414D01*
Y344364D01*
G01X820766Y354089D02*
X815541D01*
G01X806825Y420665D02*
Y419236D01*
X809702Y416359D01*
G01X815334Y390112D02*
Y386466D01*
X815600Y386200D01*
G01X828550Y422612D02*
X831650D01*
G01X811431Y403117D02*
Y396031D01*
X811300Y395900D01*
G01X890531Y-23804D02*
Y-103804D01*
G01X867851Y163585D02*
Y160855D01*
X866486Y159490D01*
G01X864992Y175435D02*
X861895D01*
X860504Y174044D01*
G01X860486Y163694D02*
Y159490D01*
G01X860504Y168044D02*
X860486Y168026D01*
Y163694D01*
G01X865048Y348715D02*
X868014D01*
X868433Y349134D01*
G01X861548Y348715D02*
X861511Y348752D01*
Y352861D01*
G01X861420Y367269D02*
X861511Y367178D01*
Y363163D01*
G01Y357163D02*
Y352861D01*
G01X1060531Y-23804D02*
Y-103804D01*
G01X1258031Y-23804D02*
Y-103804D01*
G01X1286031Y-7804D02*
G02I-12000J0D01*
G01X1280881D02*
G02I-6850J0D01*
G01X1274031Y-23804D02*
Y8196D01*
G01X1290031Y-7804D02*
X1258031D01*
X43000Y59500D03*
X51000D03*
X34000Y59400D03*
X38500Y56500D03*
X46500Y48500D03*
X28123Y453658D03*
X62276Y550493D03*
X37660Y566400D03*
X64427Y538836D03*
X67853Y558117D03*
X64701Y564416D03*
X28782Y555119D03*
X34132Y521245D03*
X34175Y526969D03*
X29165Y532612D03*
X29058Y538228D03*
X29158Y543855D03*
X28800Y549474D03*
X33697Y560866D03*
X61100Y546700D03*
X64277Y502177D03*
X67852Y539219D03*
X67853Y564416D03*
Y554967D03*
Y542368D03*
X64701Y561266D03*
X63456Y555041D03*
X67853Y561266D03*
X64701Y542366D03*
X64151Y521695D03*
X53524Y521269D03*
Y526995D03*
Y532622D03*
X52613Y538242D03*
X52408Y543876D03*
X52603Y549526D03*
X52485Y555153D03*
X53300Y560879D03*
X42597Y571789D03*
X67852Y583313D03*
X67853Y573865D03*
X67852Y586463D03*
X64701Y570716D03*
X67853Y577015D03*
X64703Y586463D03*
X64701Y567566D03*
X67853Y570715D03*
X53302Y567317D03*
X58926Y582407D03*
X28667Y634097D03*
X42550Y599224D03*
X50400Y663700D03*
X50500Y667900D03*
X64884Y650984D03*
X37961Y659909D03*
X41100Y671800D03*
X56100Y676000D03*
X86268Y58755D03*
X90768Y69755D03*
X82768D03*
X73768Y69655D03*
X78268Y66755D03*
X121233Y450900D03*
X104000Y475500D03*
X118197Y490300D03*
X108500Y475500D03*
X97074Y492891D03*
X112722Y493971D03*
X98400Y473200D03*
X140490Y488605D03*
X132777Y462639D03*
X130787Y479138D03*
X113300Y448564D03*
X118065Y448535D03*
X100600Y490750D03*
X138023Y456188D03*
X140985Y454250D03*
X135262Y475726D03*
X105350Y511850D03*
X89899Y564415D03*
X119400Y511500D03*
X135012Y510200D03*
X94473Y547093D03*
X106272Y547370D03*
X89899Y558115D03*
X138900Y525999D03*
X136974Y534479D03*
X120500Y504600D03*
X69904Y502077D03*
X75399Y502179D03*
X81094Y502166D03*
X86699Y502300D03*
X97926D03*
X74151Y545516D03*
X86750Y542368D03*
X126337Y554085D03*
X74498Y551757D03*
X130311Y546700D03*
X71002Y539219D03*
X81276Y548766D03*
X119605Y548705D03*
X86750Y539218D03*
X74076Y535966D03*
X83600Y545518D03*
X75508Y542198D03*
X89899Y545518D03*
X127300Y543200D03*
X71002Y542368D03*
X117200Y546300D03*
X89899Y539218D03*
X83600Y539219D03*
X71002Y545518D03*
X86750D03*
X122600Y557480D03*
X71002Y558117D03*
X86750Y554965D03*
Y558115D03*
X83600Y551817D03*
X71002Y564396D03*
Y561266D03*
X83600Y564415D03*
X86750D03*
X75066Y563235D03*
X83600Y561265D03*
X71002Y554967D03*
X86750Y551815D03*
X123300Y530300D03*
X119400Y521700D03*
X133800Y528500D03*
X102601Y507300D03*
X123200Y534600D03*
X78276Y545566D03*
X93744Y542019D03*
X133554Y537374D03*
X71002Y548668D03*
X92600Y535623D03*
X86750Y561265D03*
X89899D03*
X94720Y557158D03*
X92286Y521695D03*
X86659D03*
X81032D03*
X75405D03*
X69778D03*
X97913D03*
X96371Y534124D03*
X125400Y498600D03*
X140400Y607850D03*
X137000D03*
X130700D03*
X135706Y621187D03*
X119900Y621000D03*
X131200Y620600D03*
X108371Y577258D03*
X86750Y567565D03*
X89901Y587466D03*
X93048Y577014D03*
X86750Y573864D03*
X89899D03*
X71002Y577013D03*
X85400Y629784D03*
X75197Y572437D03*
X130607Y569636D03*
X126347Y569556D03*
X117400Y567650D03*
X83600Y573865D03*
X74152Y567565D03*
X86750Y586463D03*
X71002Y567565D03*
X86750Y583313D03*
X74152Y580163D03*
X83601Y580164D03*
X89899Y577014D03*
X74152Y577013D03*
X86750Y577014D03*
X96570Y581730D03*
X118900Y609900D03*
X116400Y626600D03*
X124903Y613900D03*
X124793Y617299D03*
X139500Y611200D03*
X74152Y583312D03*
X94011Y597066D03*
X101608Y596523D03*
X93048Y580164D03*
X89899Y567565D03*
X93049Y573864D03*
X93051Y587466D03*
X83600Y567565D03*
X103098Y620264D03*
X98537Y601094D03*
X102509Y601100D03*
X103109Y608572D03*
X103124Y605153D03*
X103098Y612064D03*
Y624364D03*
X113400Y617400D03*
X70700Y629000D03*
X127100Y647000D03*
X123100D03*
X119000D03*
X73427Y699285D03*
X104550Y647050D03*
X104850Y639150D03*
X111300Y705500D03*
X86028Y696439D03*
X81928Y697539D03*
X106879Y707245D03*
X125376Y701124D03*
X106635Y701465D03*
X94106Y699683D03*
X131300Y650100D03*
X135000Y650000D03*
X89868Y689124D03*
X121300Y651900D03*
X139774Y666686D03*
X119849Y709715D03*
X106355Y710745D03*
X148000Y469000D03*
X196100Y482200D03*
X170870Y492270D03*
X186254Y463761D03*
X143700Y469000D03*
X188708Y468154D03*
X175115Y463761D03*
X167821Y488301D03*
X208370Y491570D03*
X200260Y465900D03*
X211324Y489886D03*
X167656Y465300D03*
X189700Y463500D03*
X181200Y489451D03*
X155710Y485200D03*
X172300Y478400D03*
X172900Y484101D03*
X169252Y483871D03*
X213159Y460326D03*
X154334Y465100D03*
X149000Y488600D03*
X171537Y464400D03*
X201600Y486500D03*
X198200D03*
X190036Y485520D03*
X163031Y441700D03*
X153489Y481559D03*
X148490Y451286D03*
X144245Y452344D03*
X151877Y450439D03*
X155877D03*
X145000Y488600D03*
X166761Y498900D03*
X198700Y513500D03*
X203350Y506700D03*
X188600Y531500D03*
X179000Y499800D03*
X203500Y513500D03*
X191398Y509000D03*
X211700Y513500D03*
X208700Y529100D03*
X207500Y502412D03*
X145000Y497600D03*
X187500Y523700D03*
X154730Y512704D03*
X158241Y512675D03*
X170700Y513600D03*
X182870Y513832D03*
X212300Y529000D03*
X141980Y508590D03*
X146900Y512500D03*
X185615Y498015D03*
X174900Y499800D03*
X203610Y529397D03*
X179400Y525100D03*
X182964Y510414D03*
X154400Y533500D03*
X187100Y509600D03*
X195200Y513200D03*
X162537Y499000D03*
X160286Y508429D03*
X143415Y530143D03*
X171200Y509840D03*
X170800Y499800D03*
X166600Y524100D03*
X144087Y526413D03*
X174717Y524010D03*
X178869Y509793D03*
X200650Y497862D03*
X199501Y509275D03*
X191200Y522500D03*
X191300Y525900D03*
X174700Y509600D03*
X207500Y505812D03*
X158000Y499000D03*
X200200Y529200D03*
X156000Y496100D03*
X203696Y533000D03*
X156200Y535800D03*
X188834Y496920D03*
X150553Y512500D03*
X148050Y523740D03*
X196800Y497862D03*
X193200Y497000D03*
X174400Y519283D03*
X200963Y636600D03*
X212923Y615000D03*
X191210Y617900D03*
X203300Y628900D03*
X148409Y575672D03*
X144876Y590854D03*
X148409Y579353D03*
X144876Y587173D03*
X185100Y614300D03*
X179700Y615300D03*
X151800Y615400D03*
X174799Y630303D03*
X171400Y630200D03*
X199950Y614000D03*
X196100Y614050D03*
X203900Y614100D03*
X144737Y630882D03*
X200100Y633300D03*
X209193Y614249D03*
X162750Y612217D03*
X164400Y609200D03*
X182100Y629800D03*
X178200D03*
X141742Y624666D03*
X144263Y609023D03*
X151800Y610300D03*
X188899Y629597D03*
X185500Y629700D03*
X154500Y629600D03*
X195600Y646000D03*
X166500Y640300D03*
X191766Y679920D03*
X211706Y645349D03*
X208200Y645500D03*
X148249Y695765D03*
X151130Y703440D03*
X184807Y643963D03*
X188500Y686800D03*
X205827Y695000D03*
X188600Y696800D03*
X159058Y641132D03*
X142572Y640332D03*
X150872D03*
X177100Y640400D03*
X173000D03*
X193400Y639700D03*
X189500D03*
X185300D03*
X181000D03*
X198700D03*
X151949Y691715D03*
X176447Y704925D03*
X162700Y703500D03*
X162360Y706888D03*
X168273Y696434D03*
X158994Y694545D03*
X205800Y698400D03*
X210123Y662100D03*
X200000Y664200D03*
X204100Y646500D03*
X199600Y646300D03*
X195500Y696900D03*
X207000Y654400D03*
X185598Y709274D03*
X182200Y709400D03*
X143174Y666586D03*
X162100Y711215D03*
X275276Y494017D03*
X213900Y474650D03*
X227100Y490300D03*
X275300Y467300D03*
X275700Y490300D03*
X275100Y472400D03*
X264800Y467400D03*
X278800Y467500D03*
X277455Y446150D03*
X226475Y480400D03*
X254100Y440800D03*
X257950Y440600D03*
X226500Y477000D03*
X275113Y476513D03*
X266664Y493000D03*
X214808Y463300D03*
X231400Y489800D03*
X237903D03*
X267670Y485870D03*
X271100Y485900D03*
X222995Y443805D03*
X280600Y448900D03*
X214900Y490000D03*
X231476Y449662D03*
X276591Y483709D03*
X245874Y458478D03*
X242500Y458900D03*
X253400Y453500D03*
X273400Y449700D03*
X249465Y458000D03*
X252626Y469150D03*
X244400Y478600D03*
X244300Y474150D03*
X225532Y450047D03*
X237600Y455500D03*
X233664Y482859D03*
X226607Y444058D03*
X230610Y444055D03*
X234648Y540453D03*
X221960Y504230D03*
X222500Y536161D03*
X279600Y527900D03*
X272100Y537500D03*
X251346Y554100D03*
X256816Y563982D03*
X262996Y548757D03*
X231450Y563000D03*
X270021Y549394D03*
X283600Y539294D03*
X242700Y548600D03*
X252400Y539600D03*
X271715Y556690D03*
X263400Y531500D03*
X233850Y552201D03*
X234943Y565199D03*
X265100Y562300D03*
X227600Y563000D03*
X254494Y529198D03*
X248459Y523892D03*
X269100Y509063D03*
X244850Y540150D03*
X248700Y540000D03*
X228200Y496200D03*
X263600Y540700D03*
X226357Y504514D03*
X257894Y529254D03*
X263600Y535350D03*
X223800Y531600D03*
X236400Y502150D03*
X246508Y532821D03*
X228100Y545500D03*
X227100Y525400D03*
X228800Y542100D03*
X238600Y509900D03*
X228313Y552169D03*
X233100Y509800D03*
X275100D03*
X260900Y553900D03*
X242600Y509800D03*
X233607Y557671D03*
X241154Y536017D03*
X250445Y548551D03*
X255800Y539600D03*
X279200Y531600D03*
X250400Y636976D03*
X215800Y631200D03*
X260705Y598359D03*
X232896Y613795D03*
X279450Y577970D03*
X260850Y603537D03*
X274800Y607500D03*
X258600Y613100D03*
X254208Y603995D03*
X254043Y598359D03*
X247088Y610236D03*
X254821Y627000D03*
X255228Y631071D03*
X278150Y637250D03*
X229800Y593200D03*
X246800Y589600D03*
X261900Y588900D03*
X245400Y581800D03*
X264358Y608152D03*
X241300Y635900D03*
X228900Y635800D03*
X222500Y630200D03*
X218800Y635600D03*
X225900Y615000D03*
X221800Y614800D03*
X246500Y602500D03*
X234000Y628400D03*
X230900Y581600D03*
X270300Y622315D03*
X281500Y598419D03*
X231200Y576800D03*
X234700Y581600D03*
X254408Y586483D03*
X255400Y579500D03*
X225900Y630988D03*
X230063Y618667D03*
X274100Y591000D03*
X279745Y608000D03*
X255663Y617763D03*
X276376Y574132D03*
X281636Y588796D03*
X231000Y571900D03*
X242333Y593800D03*
X257346Y599169D03*
X257332Y602569D03*
X258398Y605915D03*
Y609484D03*
X218200Y609500D03*
X262694Y568076D03*
X261300Y571300D03*
X235800Y615100D03*
X233447Y603747D03*
X232300Y600300D03*
X258596Y586356D03*
X259848Y583194D03*
X279214Y591383D03*
X275652Y577455D03*
X237100Y590000D03*
X234087Y618038D03*
X248800Y582000D03*
X273022Y580751D03*
X268200Y578700D03*
X259000Y617000D03*
X234800Y572000D03*
X256007Y575050D03*
X281975Y572963D03*
X279800Y569182D03*
X264200Y574100D03*
X261810Y633980D03*
X264800Y632300D03*
X276783Y588907D03*
X258873Y631373D03*
X215400Y626800D03*
X281510Y583003D03*
X276400Y700650D03*
X254900Y701950D03*
X267500Y645600D03*
X280500Y708100D03*
X269003Y704337D03*
X282620Y640950D03*
X262826Y662274D03*
X245100Y639500D03*
X219200Y645300D03*
X230270Y645933D03*
X247725Y656375D03*
X261900Y699300D03*
X266550Y675750D03*
X247825Y670375D03*
X245971Y698400D03*
X235100Y679921D03*
X221575Y695400D03*
X279400Y686400D03*
X223013Y645672D03*
X231500Y659100D03*
X255050Y675750D03*
X271240Y698960D03*
X243731Y709100D03*
X272900Y669100D03*
X254600Y685100D03*
X278150Y648363D03*
X284000Y678300D03*
X263800Y648902D03*
X236000Y646100D03*
X272300Y665700D03*
X266398Y679250D03*
X226708Y645869D03*
X239400Y677600D03*
X267045Y695881D03*
X215606Y645300D03*
X217638Y695562D03*
X239000Y691000D03*
X276400Y697250D03*
X254700Y708900D03*
X271220Y679910D03*
X255000Y679900D03*
X235042Y656173D03*
X263500Y643212D03*
X243100Y677500D03*
X267100Y699700D03*
X266400Y662200D03*
X280600Y711700D03*
X282353Y740020D03*
X268820Y715100D03*
X262645Y712155D03*
X254648Y745463D03*
X268520Y719420D03*
X258431Y712169D03*
X268230Y723570D03*
X345069Y108533D03*
X340080Y108432D03*
X348900Y115400D03*
X340706Y128612D03*
X352000Y109000D03*
X355500D03*
X305703Y202696D03*
X306407Y206057D03*
X355300Y179300D03*
X354282Y187718D03*
Y191718D03*
X305651Y199283D03*
X294720Y182200D03*
X320700Y177800D03*
X294720Y178600D03*
Y185600D03*
X307567Y277592D03*
Y273592D03*
X304548Y272508D03*
Y268508D03*
Y265008D03*
Y261008D03*
X321432Y279090D03*
X321281Y266486D03*
X321197Y254433D03*
X306446Y247874D03*
X323842Y219284D03*
X305498Y213824D03*
X305382Y227474D03*
X323800Y227000D03*
X323700Y230600D03*
X335100Y228117D03*
X333882Y273978D03*
Y270578D03*
X335098Y233078D03*
X305782Y230874D03*
X334482Y263778D03*
X333782Y267178D03*
X324000Y222800D03*
X305782Y220674D03*
X305682Y224074D03*
X305782Y217274D03*
X334198Y248824D03*
X305454Y244461D03*
X334282Y252378D03*
X305373Y251101D03*
X306412Y254339D03*
X334260Y255820D03*
X305882Y234274D03*
X305772Y237673D03*
X305781Y241076D03*
X334107Y291354D03*
Y287354D03*
Y283854D03*
Y279854D03*
X307567Y349192D03*
X304267Y348092D03*
Y344092D03*
Y340592D03*
Y336592D03*
X307567Y335492D03*
Y331492D03*
Y327992D03*
Y323992D03*
X304267Y322892D03*
Y318892D03*
Y315392D03*
Y311392D03*
X307567Y310292D03*
Y306292D03*
Y302792D03*
Y298792D03*
X304267Y297692D03*
Y293692D03*
Y290192D03*
Y286192D03*
X334582Y341721D03*
Y337721D03*
Y334221D03*
Y330221D03*
X328187Y350316D03*
Y346816D03*
Y342816D03*
X328182Y329124D03*
Y325124D03*
Y321624D03*
Y317624D03*
X334593Y316584D03*
Y312584D03*
Y309084D03*
Y305084D03*
X328182Y303977D03*
Y299977D03*
Y296477D03*
Y292477D03*
X307567Y285092D03*
Y281092D03*
X321432Y342082D03*
Y329484D03*
Y316885D03*
X321882Y304374D03*
Y291874D03*
X304267Y373292D03*
Y369292D03*
Y365792D03*
Y361792D03*
X307567Y360692D03*
Y356692D03*
Y353192D03*
X328182Y379518D03*
Y375518D03*
Y372018D03*
Y368018D03*
X334582Y366974D03*
Y362974D03*
Y359474D03*
Y355474D03*
X328187Y354316D03*
X320832Y367479D03*
X321432Y354681D03*
X320932Y377074D03*
X340606Y389899D03*
X336000Y384400D03*
X336230Y377800D03*
X350408Y393708D03*
X348006Y391300D03*
X321859Y388315D03*
X321100Y384874D03*
X346300Y374600D03*
X349100Y379100D03*
X303900Y380574D03*
X348997Y491678D03*
X295700Y428400D03*
X344900Y442800D03*
X344688Y493896D03*
X343050Y438900D03*
X339900Y454000D03*
X328313Y435513D03*
X324916Y435360D03*
X321700Y436650D03*
X296254Y546706D03*
X305350Y514300D03*
X292200Y542473D03*
X285800Y549394D03*
X346440Y527500D03*
X350879Y520400D03*
X352734Y541826D03*
X355700Y510000D03*
X344600Y511800D03*
X326900Y507700D03*
X304800Y554443D03*
X318200Y522900D03*
X285833Y557629D03*
X302700Y551300D03*
X339062Y521100D03*
X344600Y507600D03*
X341300Y536200D03*
X352921Y536521D03*
X311900Y514900D03*
X287500Y518000D03*
X297850Y524500D03*
X293600Y518400D03*
X313300Y518800D03*
X354300Y500245D03*
X288311Y496200D03*
X355600Y506600D03*
X298200Y521100D03*
X301300Y524400D03*
X355600Y513500D03*
X327300Y540100D03*
X341400Y560050D03*
X307800Y546700D03*
X341615Y556015D03*
X305913Y549643D03*
X331900Y549700D03*
X329050Y552315D03*
X348220Y563836D03*
X344812Y563844D03*
X344755Y497841D03*
X304436Y564081D03*
X341349Y563750D03*
X307350Y561290D03*
X335000Y497000D03*
X332698Y543738D03*
X330200Y535200D03*
X331000Y522100D03*
X302665Y547006D03*
X302506Y543341D03*
X327403Y543499D03*
X336723Y542000D03*
X327800Y514900D03*
X330200Y531800D03*
X323400Y507540D03*
X336800Y506300D03*
X286061Y502378D03*
X293970Y564927D03*
X335000Y500600D03*
X298719Y542538D03*
X293500Y522600D03*
X334811Y551476D03*
X311900Y511500D03*
X309600Y520150D03*
X312300Y540600D03*
X332940Y539287D03*
X333400Y503800D03*
X322900Y530600D03*
X327417Y548344D03*
X290000Y503200D03*
X293800Y503300D03*
X299100Y589200D03*
X304124Y570227D03*
X341750Y630790D03*
X342330Y620300D03*
X344940Y617720D03*
X292400Y637000D03*
X341690Y609930D03*
X341210Y602420D03*
X330800Y602610D03*
X317572Y603183D03*
X305470Y623734D03*
X307542Y588138D03*
X334923Y579949D03*
X353500Y624500D03*
X353669Y600881D03*
X302300Y582000D03*
X286700Y611911D03*
X340920Y575234D03*
X348000Y612661D03*
X352472Y581000D03*
X325762Y596900D03*
X324900Y581600D03*
X291839Y578193D03*
X293697Y589566D03*
X289070Y573080D03*
X355700Y579317D03*
X341755Y627231D03*
Y623682D03*
X341600Y616962D03*
Y613413D03*
X334264Y602648D03*
X337813D03*
X352716Y594135D03*
X350746Y574837D03*
X293500Y625600D03*
X293600Y629100D03*
X321421Y605265D03*
X323413Y602491D03*
X303000Y586800D03*
X292006Y574797D03*
X315616Y571817D03*
X289800Y569182D03*
X315893Y567721D03*
X341558Y567689D03*
X300043Y603619D03*
X303468Y603647D03*
X352716Y590535D03*
X347784Y587509D03*
X336923Y586749D03*
X347784Y584109D03*
X336923Y583349D03*
X307650Y596000D03*
X285400Y572556D03*
X325761Y592959D03*
X315315Y575204D03*
X317813Y580469D03*
X286400Y569200D03*
X317813Y584969D03*
X325899Y589186D03*
X297118Y668882D03*
X294804Y695204D03*
X292400Y640500D03*
X332824Y684270D03*
X348314Y643853D03*
X332800Y691970D03*
X318000Y678270D03*
X304100Y666500D03*
X351547Y645938D03*
X355100Y651827D03*
X314398Y670254D03*
X340000Y662200D03*
X353700Y670900D03*
X352800Y702960D03*
X328356Y678679D03*
X297900Y664800D03*
X290600Y668200D03*
X338301Y673907D03*
X328600Y661100D03*
X343372Y655836D03*
X347013Y656090D03*
X328087Y701587D03*
X327062Y697600D03*
X332200Y643800D03*
X288720Y641455D03*
X289473Y657061D03*
X336000Y662200D03*
X336387Y648987D03*
X317516Y671612D03*
X315000Y674900D03*
X338135Y670511D03*
X342542Y685983D03*
X342645Y682506D03*
X300700Y667000D03*
X330593Y671019D03*
X303741Y654095D03*
X329989Y653920D03*
X298570Y743670D03*
X306470Y743570D03*
X291700Y737000D03*
X316465Y716063D03*
X287220Y737920D03*
X334000Y714640D03*
X293075Y726600D03*
X342208Y714950D03*
X337481Y719818D03*
X380500Y33500D03*
Y30000D03*
X382631Y48200D03*
X382547Y52800D03*
X375300Y62150D03*
X384000Y30000D03*
X425765Y56265D03*
X372500Y44500D03*
Y56500D03*
X375300Y72050D03*
X357500Y104200D03*
X394070Y80840D03*
X385964Y80089D03*
X382500Y88000D03*
X376000Y78400D03*
X366500Y124700D03*
X363100Y124600D03*
X387833Y82930D03*
X391382D03*
X372500Y90000D03*
Y78000D03*
X396800Y74800D03*
X405100Y159300D03*
X400000Y159200D03*
X365900Y198500D03*
X365800Y193750D03*
X399900Y152100D03*
X400924Y155896D03*
X404473D03*
X398000Y165400D03*
X398050Y162000D03*
X406400Y150300D03*
X362150Y214174D03*
X364000Y240100D03*
X363828Y243944D03*
X381009Y343909D03*
X380799Y347303D03*
X386250Y318250D03*
X380600Y335700D03*
X373700Y329700D03*
X376910Y366078D03*
X359323Y372277D03*
X363699Y382608D03*
X363703Y386008D03*
X363586Y375809D03*
X363701Y379208D03*
X377300Y362700D03*
X379448Y487250D03*
X361250Y491650D03*
X363942Y450591D03*
X366700Y454800D03*
X359400Y451600D03*
X381276Y469106D03*
X374030Y449526D03*
X372575Y452600D03*
X380200Y457800D03*
X381400Y462000D03*
X370800Y475128D03*
X389081Y475224D03*
X387950Y466800D03*
X394700Y481700D03*
X394952Y485300D03*
X378937Y443491D03*
X376697Y446050D03*
X373576Y466300D03*
X373534Y462830D03*
X370900Y471700D03*
X373700Y482700D03*
X377691Y451891D03*
X381370Y465500D03*
X388123Y492432D03*
X378840Y448690D03*
X361013Y475128D03*
X368100Y513100D03*
X387800Y529400D03*
X367500Y526800D03*
X393100Y564400D03*
X362801Y548097D03*
X366900Y499942D03*
X372714Y509275D03*
X364000Y525500D03*
X387400Y547500D03*
X384400Y545195D03*
X362666Y504265D03*
X390651Y499000D03*
X387800Y525500D03*
X387700Y521600D03*
X376617Y544817D03*
X397650Y508250D03*
Y536671D03*
X362280Y554590D03*
X397650Y519400D03*
X394880Y548670D03*
X397650Y523900D03*
X393465Y553100D03*
X387700Y517700D03*
X362500Y499970D03*
X365730Y541050D03*
X368900Y505000D03*
X372494Y513020D03*
X383126Y565162D03*
X366490Y564360D03*
X370763Y547900D03*
X370800Y551300D03*
Y554700D03*
X383080Y554897D03*
X384347Y558647D03*
X382922Y561735D03*
X372900Y538700D03*
X396400Y545500D03*
X393889Y543207D03*
X396200Y597200D03*
X394800Y609700D03*
X358646Y596456D03*
X359000Y635600D03*
X360980Y582586D03*
X394300Y576600D03*
X372951Y576851D03*
X377714Y631280D03*
X368399Y567372D03*
X367133Y596067D03*
X382380Y612620D03*
X371180Y629236D03*
X386224Y580524D03*
X383411Y577024D03*
X362250Y570875D03*
X364300Y592900D03*
X361227Y630300D03*
X378400Y594800D03*
X365953Y570753D03*
X382600Y609000D03*
X375700Y580102D03*
X390600Y625500D03*
X366100Y590000D03*
X380572Y592095D03*
X396300Y587000D03*
X396400Y583500D03*
X388418Y650549D03*
X385700Y641300D03*
X374200Y645871D03*
X374252Y641029D03*
X386050Y701200D03*
X379100Y703300D03*
X363664Y688950D03*
X384466Y661650D03*
X378832Y659705D03*
X388338Y643600D03*
Y647149D03*
X392100Y683900D03*
X392000Y679800D03*
X390500Y665800D03*
Y669200D03*
X396306Y698732D03*
X361914Y680181D03*
X401000Y676500D03*
X371457Y667593D03*
X368060Y667743D03*
X392079Y703434D03*
X396400Y659800D03*
X390355Y690926D03*
X373060Y702960D03*
X398600Y662700D03*
X379450Y714400D03*
X383600Y711800D03*
X372100Y711700D03*
X478426Y20427D03*
X496394Y30000D03*
X482727Y41870D03*
X486535Y47449D03*
X482397Y52176D03*
X472800Y50000D03*
X469000Y50100D03*
X499721Y46102D03*
X499623Y49524D03*
X446788Y55180D03*
X458041Y47341D03*
X476100Y60500D03*
X478700Y62800D03*
X462372Y49179D03*
X486400Y38500D03*
X467016Y20430D03*
X450454Y38147D03*
X486527Y41939D03*
X447233Y48829D03*
X496355Y26000D03*
X496242Y22287D03*
X460300Y57600D03*
X432269Y19980D03*
X486700Y31100D03*
X462874Y95922D03*
X487500Y73400D03*
X485700Y70500D03*
X448000Y80404D03*
X444800Y82404D03*
X478590Y70310D03*
X482200Y70500D03*
X498500Y84200D03*
X471281Y105681D03*
X455766Y114535D03*
X473600Y108300D03*
X457000Y117800D03*
X480538Y112071D03*
X459500Y95500D03*
X441100Y110950D03*
X448996Y117666D03*
X463479Y99412D03*
X504900Y18200D03*
X508646Y18386D03*
X518890Y59730D03*
X515700Y50899D03*
X515785Y55552D03*
X505633Y46932D03*
X502300Y58200D03*
X528300Y58648D03*
X515500Y59000D03*
X513500Y62000D03*
X532500Y58600D03*
X513379Y103325D03*
X502379Y103194D03*
X543059Y108958D03*
X540800Y111500D03*
X501100Y86800D03*
X538456Y65144D03*
X509981Y103194D03*
X505779D03*
X513300Y83000D03*
X503700Y107600D03*
X599254Y37967D03*
X582447Y50607D03*
X588647Y28007D03*
X576649Y39585D03*
X575300Y45967D03*
X586754Y53967D03*
X577847Y50807D03*
X582797Y31807D03*
X600847Y33907D03*
X588753Y24080D03*
X603747Y71407D03*
X636647Y64300D03*
X642998Y127863D03*
X642574Y131843D03*
X710550Y18550D03*
X685907Y30622D03*
X673647Y33107D03*
X680300Y17500D03*
X680000Y23900D03*
X675903Y29541D03*
X668531Y71500D03*
X713200Y387700D03*
X700900Y423800D03*
X696070Y483486D03*
X712874Y470182D03*
X707391Y484208D03*
X712000Y442100D03*
X711300Y423800D03*
X701183Y453339D03*
X704836D03*
X709700Y480332D03*
X698651Y428165D03*
X669749Y458022D03*
X683000Y447200D03*
X680200Y449500D03*
X705450Y440950D03*
X705700Y493500D03*
X708367Y491000D03*
X715000Y547027D03*
X705853Y549017D03*
X708682Y551846D03*
X711156Y554320D03*
X713985Y557149D03*
X696624Y548249D03*
X699453Y551078D03*
X701927Y553552D03*
X704756Y556381D03*
X683369Y549269D03*
X686198Y552098D03*
X688672Y554572D03*
X691501Y557401D03*
X681989Y540183D03*
X684818Y543012D03*
X687292Y545486D03*
X690121Y548315D03*
X668195Y541742D03*
X671024Y544571D03*
X673498Y547045D03*
X676327Y549874D03*
X655092Y536171D03*
X657921Y539000D03*
X660395Y541474D03*
X663224Y544303D03*
X713189Y524511D03*
X707283D03*
X701378D03*
X695472D03*
X689567D03*
X683661D03*
X677756D03*
X662400Y519500D03*
X666800D03*
X657199Y530195D03*
X671850Y524511D03*
X653634Y513757D03*
X656846Y521702D03*
X678740Y508760D03*
X777500Y34500D03*
X766200Y22000D03*
X723800Y18600D03*
X725288Y405950D03*
X783800Y422800D03*
X718300Y387700D03*
X740500Y426800D03*
X716100Y442100D03*
X721100D03*
X725200D03*
X740500Y431000D03*
X723800Y475164D03*
X785434Y551934D03*
X788263Y554763D03*
X775934Y550934D03*
X778763Y553763D03*
X781237Y556237D03*
X784066Y559066D03*
X765434Y549934D03*
X768263Y552763D03*
X770737Y555237D03*
X773566Y558066D03*
X753434Y545434D03*
X756263Y548263D03*
X758737Y550737D03*
X761566Y553566D03*
X725853Y547117D03*
X728682Y549946D03*
X731156Y552420D03*
X733985Y555249D03*
X717829Y549856D03*
X720303Y552330D03*
X723132Y555159D03*
X716536Y523519D03*
X720536D03*
X724036D03*
X728036D03*
X762679Y535537D03*
X742716Y536435D03*
X738779D03*
X782086D03*
X776181D03*
X770275D03*
X725000D03*
X719394Y536305D03*
X759342Y543603D03*
X765935Y537009D03*
X777165Y509835D03*
X854596Y155288D03*
X840122Y156614D03*
X843160Y169467D03*
X845168Y192764D03*
X851137Y199864D03*
X858622Y155614D03*
X854634Y166390D03*
X842511Y164078D03*
X842022Y152174D03*
X858632Y216929D03*
X857700Y222300D03*
X848868Y219064D03*
X850730Y350483D03*
X841116Y348914D03*
X820059Y331701D03*
X835316Y340914D03*
X846456Y350814D03*
X808188Y404950D03*
X815541Y354089D03*
X847720Y371072D03*
X856720Y409372D03*
X809702Y416359D03*
X822300Y418900D03*
X831650Y422612D03*
X830531Y361589D03*
X794200Y422800D03*
X811300Y395900D03*
X801200Y386700D03*
X796100D03*
X821800Y400500D03*
X821700Y403900D03*
X842820Y382172D03*
X816997Y371022D03*
X847629Y391998D03*
X855320Y414472D03*
X830133Y353930D03*
X842916Y357214D03*
X849420Y407748D03*
X822300Y390000D03*
X804000Y441100D03*
X799000D03*
X811142Y470358D03*
X811668Y433703D03*
X820150Y433900D03*
X794900Y441100D03*
X808100D03*
X807400Y477229D03*
X823710Y469835D03*
X803300Y491600D03*
X806888Y491398D03*
X822434Y550434D03*
X825263Y553263D03*
X827737Y555737D03*
X830566Y558566D03*
X809934Y545434D03*
X812763Y548263D03*
X815237Y550737D03*
X818066Y553566D03*
X803934Y551934D03*
X806763Y554763D03*
X809237Y557237D03*
X812066Y560066D03*
X794934Y551434D03*
X797763Y554263D03*
X800237Y556737D03*
X803066Y559566D03*
X790737Y557237D03*
X793566Y560066D03*
X845198Y552063D03*
X842369Y549234D03*
X839895Y546760D03*
X837066Y543931D03*
X825000Y536200D03*
X817519Y536435D03*
X811614D03*
X805708D03*
X841141D03*
X837204D03*
X799803D03*
X793897D03*
X787992D03*
X867653Y172764D03*
X867851Y163585D03*
X864492Y206435D03*
X860868Y219764D03*
X868433Y349134D03*
X864920Y368972D03*
X861484Y399069D03*
G54D31*
X137824Y544746D03*
Y552346D03*
X135449Y558949D03*
Y566549D03*
X122600Y594800D03*
Y602400D03*
X149700Y723000D03*
Y715400D03*
X228201Y518368D03*
Y510768D03*
X249500Y616500D03*
Y624100D03*
X241800Y624000D03*
Y616400D03*
X311057Y193874D03*
Y201474D03*
X318763Y220690D03*
Y228290D03*
X311097Y220715D03*
Y228315D03*
X329435Y225684D03*
Y218084D03*
X477343Y33619D03*
Y41219D03*
X663847Y39907D03*
Y32307D03*
X655847Y39907D03*
Y32307D03*
X677447Y478527D03*
Y470927D03*
X699365Y510653D03*
Y518253D03*
X749875Y523096D03*
Y530696D03*
X779239Y522260D03*
Y529860D03*
X800291Y509468D03*
Y517068D03*
X885359Y223815D03*
Y216215D03*
X901690Y397644D03*
Y405244D03*
X894072Y397625D03*
Y405225D03*
X866541Y392586D03*
Y400186D03*
G54D40*
X96287Y572899D03*
X143823Y612046D03*
X250300Y630000D03*
X354662Y519446D03*
X308700Y511900D03*
X360980Y586886D03*
X586447Y57207D03*
X806825Y420615D03*
X815334Y390062D03*
G54D22*
X31100Y512700D03*
X37500Y579400D03*
X126330Y445098D03*
X108492Y541948D03*
X102500Y499700D03*
X130400Y539900D03*
X126780Y562773D03*
X134800Y604800D03*
X137100Y589427D03*
X138970Y632277D03*
X117121Y579999D03*
X128700Y615500D03*
X138700Y636655D03*
X139400Y615000D03*
X113672Y605134D03*
X113512Y613401D03*
X113426Y609234D03*
X108137Y615870D03*
X113400Y621400D03*
X133835Y609620D03*
X134354Y632246D03*
X94818Y655471D03*
X118998Y701124D03*
X115598Y708228D03*
X133000Y656400D03*
X89560Y712200D03*
X109478Y713245D03*
X183900Y493100D03*
X147100Y483400D03*
X144943Y480031D03*
X178500Y492200D03*
X167999Y479200D03*
X149000Y494500D03*
X179100Y455800D03*
X207300Y471520D03*
X208400Y476900D03*
X207500Y483000D03*
X176252Y473571D03*
X176224Y468472D03*
X194411Y485447D03*
X193400Y463300D03*
X174036Y448700D03*
X151016Y445380D03*
X181938Y444600D03*
X190999Y446650D03*
X145000Y492200D03*
X187964Y493426D03*
X197847Y494417D03*
X167680Y510640D03*
X187699Y543279D03*
X187800Y547278D03*
X178200Y540400D03*
X209627Y540605D03*
X163300Y510400D03*
X174930Y534600D03*
X164784Y539407D03*
X167000Y535500D03*
X158200Y532900D03*
X183750Y524200D03*
X190936Y540928D03*
X176900Y496500D03*
X177600Y517400D03*
X198796Y505657D03*
X200402Y542169D03*
X203930Y540283D03*
X154400Y524400D03*
X190929Y512592D03*
X203356Y495487D03*
X199162Y602800D03*
X152640Y582742D03*
X197611Y630698D03*
X193400Y630600D03*
X184932Y601225D03*
X180571Y611325D03*
X177200Y633500D03*
X172449Y633644D03*
X156500Y598500D03*
X190944Y605862D03*
X199950Y617600D03*
X195500Y618000D03*
X200500Y622000D03*
X206800Y627047D03*
X207450Y622000D03*
X208423Y605303D03*
X165000Y614300D03*
X161047Y615989D03*
X160088Y608100D03*
X159500Y612300D03*
X153000Y594927D03*
X148210Y629830D03*
X148400Y607000D03*
X179344Y607509D03*
X155950Y592010D03*
X162500Y624850D03*
X173247Y607000D03*
X172848Y700108D03*
X150849Y710215D03*
X155846Y723282D03*
X240900Y440900D03*
X236400Y440800D03*
X280587Y491768D03*
X280700Y484600D03*
X239100Y450500D03*
X223146Y489341D03*
X267435Y442572D03*
X245800Y443600D03*
X215300Y512200D03*
X235002Y562120D03*
X224600Y560900D03*
X230277Y559321D03*
X214235Y539198D03*
X246400Y547900D03*
X246463Y553137D03*
X224900Y497730D03*
X260000Y517300D03*
X279654Y497255D03*
X279000Y555000D03*
X252500Y563200D03*
X229807Y530200D03*
X224000Y539130D03*
X225500Y557000D03*
X258300Y504750D03*
X256500Y552900D03*
X240274Y629709D03*
X213400Y621100D03*
X219466Y628146D03*
X251100Y595000D03*
X236400Y568800D03*
X265231Y570631D03*
X237500Y578550D03*
X236800Y574297D03*
X218300Y605000D03*
X221000Y601900D03*
X215900Y595500D03*
X232536Y588078D03*
X218298Y591749D03*
X226195Y603279D03*
X264750Y580250D03*
X247400Y576400D03*
X260096Y574693D03*
X249361Y693100D03*
X277600Y680200D03*
X218925Y666220D03*
X267584Y656531D03*
X250128Y678106D03*
X250900Y642100D03*
X331321Y198570D03*
X334200Y205400D03*
X335100Y237500D03*
X315866Y214556D03*
X328451Y207719D03*
X312800Y244461D03*
X321900Y249400D03*
X324600Y252600D03*
X330806Y392324D03*
X293326Y494174D03*
X339507Y433648D03*
X351597Y438869D03*
X354158Y430400D03*
X293800Y534000D03*
X292200Y548564D03*
X308253Y535182D03*
X288000Y561000D03*
X290590Y509859D03*
X336881Y530496D03*
X336953Y534506D03*
X331806Y561752D03*
X328012Y556569D03*
X318970Y565209D03*
X337600Y515500D03*
X339300Y526300D03*
X331240Y500920D03*
X331600Y512900D03*
X334900Y557600D03*
X316700Y631700D03*
X355200Y607700D03*
X345386Y604896D03*
X319401Y569678D03*
X347398Y599694D03*
X309765Y608200D03*
X348161Y592261D03*
X319831Y573790D03*
X315411Y701965D03*
X352600Y674489D03*
X290951Y673641D03*
X352557Y679888D03*
X317159Y667813D03*
X311798Y673233D03*
X325332Y685592D03*
X316550Y663250D03*
X327368Y651299D03*
X310100Y677950D03*
X297330Y682986D03*
X313000Y658500D03*
X291754Y680486D03*
X365000Y75500D03*
X387500Y458200D03*
X378200Y476600D03*
X383700Y500800D03*
X357379Y552518D03*
X357853Y500825D03*
X374049Y517383D03*
X357400Y559500D03*
X390769Y495379D03*
X384500Y616500D03*
X383313Y621780D03*
X375000Y573200D03*
X385700Y586100D03*
X366500Y586300D03*
X376676Y568400D03*
X395127Y568056D03*
X395100Y572899D03*
X364600Y670800D03*
X479040Y47134D03*
X488800Y62100D03*
X461350Y29800D03*
X443869Y43095D03*
X488974Y44580D03*
X483091Y33900D03*
X452490Y64240D03*
X457585Y70015D03*
X531050Y46998D03*
X544309Y39634D03*
X563620Y60160D03*
X530031Y32071D03*
X508855Y40905D03*
X534956Y62900D03*
X502400Y64400D03*
X588200Y44800D03*
X591347Y53907D03*
X603847Y60757D03*
X633137Y19759D03*
X579158Y73212D03*
X648910Y40090D03*
X669505Y41254D03*
X700689Y491390D03*
X704486Y488179D03*
X697100Y450200D03*
X681500Y501000D03*
X775100Y540000D03*
X754829Y502218D03*
X724242Y504713D03*
X764254Y544790D03*
X851008Y186924D03*
X853697Y161250D03*
X852922Y207800D03*
X834116Y330314D03*
X813916Y338614D03*
X846295Y383181D03*
X848820Y395572D03*
X839643Y390800D03*
X836284Y352842D03*
X835820Y380672D03*
X815600Y398300D03*
X825000Y428800D03*
X829700Y426800D03*
X798600Y502500D03*
X792300Y502200D03*
X864992Y175435D03*
X860486Y163694D03*
X870228Y217843D03*
X899400Y235700D03*
X898300Y284200D03*
X870447Y281493D03*
X870568Y302548D03*
X866800Y406100D03*
X887718Y375178D03*
X861420Y367269D03*
X861511Y352861D03*
X900379Y391262D03*
X860398Y394819D03*
G54D13*
X30900Y79600D03*
X81169Y734566D03*
X847271Y45720D03*
G54D41*
X133600Y614300D03*
X204800Y487100D03*
X166761Y492320D03*
X212165Y483008D03*
X191694Y532628D03*
X170800Y503100D03*
X211378Y532401D03*
X166737Y502154D03*
X179000Y503100D03*
X207278Y532401D03*
X162537Y502154D03*
X200031Y532794D03*
X147247Y501787D03*
X151351Y501797D03*
X158294Y502154D03*
X192471Y610938D03*
X188431Y609938D03*
X147723Y612196D03*
X217908Y479635D03*
X222100Y475200D03*
X233300Y543700D03*
X237300D03*
X246980Y558568D03*
X219473Y532173D03*
X221800Y608300D03*
X225900Y608200D03*
X273895Y567952D03*
X272900Y584300D03*
X242600Y575100D03*
X269806Y567952D03*
X330600Y505900D03*
X288286Y583855D03*
X351500Y584090D03*
X314800Y678000D03*
X357000Y586800D03*
X373400Y622600D03*
X498150Y55330D03*
X459610Y33640D03*
X493500Y63900D03*
X511500Y54800D03*
X837816Y344414D03*
X848820Y400072D03*
G54D23*
X54100Y586350D03*
X46500D03*
X100100Y705700D03*
X92500D03*
X325629Y183698D03*
X318029D03*
X325705Y191549D03*
X318105D03*
X328900Y235400D03*
X321300D03*
X685200Y490609D03*
X692800D03*
X888326Y201329D03*
X895926D03*
X885501Y209131D03*
X893101D03*
X869245Y212185D03*
X861645D03*
X881986Y275745D03*
X889586D03*
X881986Y299745D03*
X889586D03*
X881986Y307745D03*
X889586D03*
X881986Y291745D03*
X889586D03*
X881986Y283745D03*
X889586D03*
X885914Y398288D03*
X878314D03*
G54D32*
X78525Y554363D03*
X78524Y558398D03*
X98044Y555240D03*
X98076Y560166D03*
X139800Y620200D03*
X126200Y626300D03*
X184800Y489000D03*
X199400Y483000D03*
X168101Y469168D03*
Y473268D03*
X171500Y526700D03*
X198846Y501509D03*
X200600Y608800D03*
X172402Y574058D03*
X198755Y625814D03*
X159700Y619900D03*
X149557Y602562D03*
X145800Y596700D03*
X204000Y638200D03*
X176034Y619120D03*
X147600Y620200D03*
X211700Y642200D03*
X241400Y543700D03*
X226357Y534556D03*
X238000Y556100D03*
Y551900D03*
X229700Y505300D03*
X255861Y548308D03*
X247600Y536200D03*
X255200Y535800D03*
X235500Y593500D03*
X228192Y622802D03*
X223000Y597200D03*
Y593200D03*
X224000Y571900D03*
X224375Y576816D03*
X224300Y585900D03*
X228000Y567000D03*
X265300Y584500D03*
X263288Y666467D03*
X222092Y642006D03*
X328100Y387774D03*
X342200Y377800D03*
X320725Y558073D03*
X324585Y566198D03*
X344200Y579231D03*
X324756Y571267D03*
X305817Y682959D03*
X362280Y544200D03*
X375915Y617425D03*
X357435Y661505D03*
X493818Y42607D03*
X490250Y33781D03*
X507300Y65000D03*
X535006Y68742D03*
X700891Y484208D03*
X693400Y455000D03*
X698300Y442100D03*
X825100Y422612D03*
X811481Y403117D03*
G54D50*
X346457Y57007D03*
X353543Y62913D03*
Y55039D03*
X346457Y66850D03*
Y74724D03*
Y84567D03*
X353543Y86535D03*
Y78661D03*
Y70787D03*
G54D14*
G01X121643Y618077D02*
Y619257D01*
X119900Y621000D01*
G01X118998Y701124D02*
X125376D01*
G01X106879Y707245D02*
X109200Y704924D01*
Y704630D01*
X112706Y701124D01*
X118998D01*
G01X162700Y703500D02*
X162698Y703498D01*
X155246D01*
X152211Y700463D01*
X129241D01*
X123655Y706049D01*
X117777D01*
X115598Y708228D01*
G01D02*
X113081Y710745D01*
X106355D01*
G01X121300Y651900D02*
X121624Y652224D01*
X136976D01*
X144100Y645100D01*
X176400D01*
X189800Y658500D01*
X210683D01*
X212183Y657000D01*
X232654D01*
X234384Y658730D01*
X251246D01*
X258974Y651002D01*
X274068D01*
X274070Y651004D01*
X279896D01*
X285953Y657061D01*
X289473D01*
G01X100100Y705700D02*
Y709600D01*
X102700Y712200D01*
G01X109478Y713245D02*
X116319D01*
X119849Y709715D01*
G01X102700Y712200D02*
X103745Y713245D01*
X109478D01*
G01X183710Y476640D02*
X190540D01*
X196100Y482200D01*
G01X140550Y498540D02*
X144060D01*
X145000Y497600D01*
G01X147723Y612146D02*
X149400Y610469D01*
Y609900D01*
X153149Y606151D01*
Y605513D01*
G01X191210Y617900D02*
X190998Y617688D01*
X188160D01*
G01X192471Y614388D02*
Y616639D01*
X191210Y617900D01*
G01X143823Y612096D02*
X147673D01*
X147723Y612146D01*
G01X203300Y628900D02*
X202205Y627805D01*
Y625814D01*
G01X156299Y570866D02*
X155738Y570305D01*
X152266D01*
G01X151949Y691715D02*
X157732Y697498D01*
X165184D01*
X167794Y700108D01*
X172848D01*
G01D02*
X174220D01*
X176447Y702335D01*
Y704925D01*
G01X249361Y693100D02*
X227806D01*
X227336Y692630D01*
X178440D01*
X177270Y693800D01*
X170907D01*
X168273Y696434D01*
G01X199600Y646300D02*
X200600D01*
X203550Y643350D01*
Y642300D01*
G01X219160Y504230D02*
X221960D01*
G01X234648Y540453D02*
X233300Y541801D01*
Y543650D01*
G01X267045Y695881D02*
X264264Y693100D01*
X249361D01*
G01X350879Y520400D02*
X352685D01*
X353589Y519496D01*
X354662D01*
G01X326900Y507700D02*
Y509000D01*
X325560Y510340D01*
X322850D01*
G01X313300Y518800D02*
X320900D01*
X322850Y516850D01*
Y515460D01*
G01X396306Y698732D02*
X398900Y696138D01*
Y673400D01*
X404600Y667700D01*
Y520000D01*
X403950Y519350D01*
Y335950D01*
X386250Y318250D01*
G01X368250Y517540D02*
X368100Y517390D01*
Y513100D01*
G01X363450Y567375D02*
X368400D01*
Y567372D01*
X368399D01*
G01X567700Y28240D02*
X557060Y17600D01*
X522900D01*
X519300Y21200D01*
X499700D01*
X495300Y16800D01*
X435449D01*
X432269Y19980D01*
G01X588200Y44800D02*
X588116Y44884D01*
Y44938D01*
X582447Y50607D01*
G01X588200Y44800D02*
X595033Y37967D01*
X599254D01*
G01X591347Y53907D02*
X586814D01*
X586754Y53967D01*
G01X586447Y57257D02*
X589597D01*
X591347Y55507D01*
Y53907D01*
G01X603847Y60757D02*
X599310D01*
X596660Y63407D01*
X589097D01*
X586447Y60757D01*
G01X603847D02*
X633104D01*
X636647Y64300D01*
G01X633137Y19759D02*
X585991D01*
X579816Y25934D01*
Y48838D01*
X577847Y50807D01*
G01X673647Y33107D02*
Y23947D01*
X669459Y19759D01*
X633137D01*
G01X600847Y33907D02*
X584897D01*
X582797Y31807D01*
G01X867653Y172764D02*
Y178979D01*
X865032Y181600D01*
X856332D01*
X851008Y186924D01*
G01X845168Y192764D02*
X851008Y186924D01*
G01X851137Y199864D02*
Y206015D01*
X852922Y207800D01*
G01X857700Y222300D02*
X847804D01*
X840568Y215064D01*
Y179664D01*
X850368Y169864D01*
Y164579D01*
X853697Y161250D01*
G01X858622Y155614D02*
X853697Y160539D01*
Y161250D01*
G01X848868Y219064D02*
X843068Y213264D01*
Y180700D01*
X853154Y170614D01*
Y167870D01*
X854634Y166390D01*
G01X858632Y216929D02*
X861645Y213916D01*
Y212185D01*
G01X860868Y219764D02*
X857118D01*
X855221Y217867D01*
Y210099D01*
X852922Y207800D01*
G01X884036Y269745D02*
Y268474D01*
X883133Y267571D01*
X852281D01*
X846696Y273156D01*
Y295208D01*
X807803Y334101D01*
Y361926D01*
X816508Y370631D01*
X816606D01*
X816997Y371022D01*
G01X837816Y347864D02*
Y351310D01*
X836284Y352842D01*
G01X830133Y353930D02*
X829549D01*
X828266Y352647D01*
Y350214D01*
G01X842820Y382172D02*
X843829Y383181D01*
X846295D01*
G01D02*
X849817D01*
G01D02*
X850667Y382331D01*
Y377675D01*
X856726Y371616D01*
X862276D01*
X864920Y368972D01*
G01X848820Y395572D02*
Y393189D01*
X847629Y391998D01*
G01X848820Y400022D02*
Y395572D01*
G01X839643Y390800D02*
Y394345D01*
X848820Y403522D01*
G01X839643Y390800D02*
Y375615D01*
X846055Y369203D01*
Y351215D01*
X846456Y350814D01*
G01X855320Y414472D02*
X853199Y412351D01*
Y407901D01*
X848820Y403522D01*
G01X836284Y352842D02*
X835196Y353930D01*
X830133D01*
G01X864492Y206435D02*
X869245Y211188D01*
Y212185D01*
G01X870790Y222573D02*
Y218405D01*
X870228Y217843D01*
G01X869245Y212185D02*
Y216860D01*
X870228Y217843D01*
G01X860398Y394819D02*
Y397983D01*
X861484Y399069D01*
G01X866541Y392586D02*
X862791D01*
X862706Y392671D01*
X862546D01*
X860398Y394819D01*
G01X866541Y392586D02*
X871745D01*
X872798Y391533D01*
X34652Y111485D03*
X33297Y703990D03*
X89764Y238386D03*
X90157Y413582D03*
X148206Y21054D03*
X201801Y684252D03*
X261147Y405580D03*
X225601Y684252D03*
X309055Y157677D03*
X305906Y182874D03*
Y388386D03*
X309252Y413583D03*
X488838Y137225D03*
Y164744D03*
X486498Y356293D03*
X706299Y83661D03*
Y201771D03*
X666929Y510236D03*
X765354D03*
X745669D03*
X804724Y83661D03*
Y201772D03*
X844094Y510236D03*
X807831Y734367D03*
X899219Y47960D03*
G54D24*
X41868Y567316D03*
X49250Y580250D03*
X96900Y712200D03*
X189771Y559210D03*
X197030Y583440D03*
X870990Y222573D03*
G54D15*
X70865Y98425D03*
Y472441D03*
X49212Y740157D03*
X314960Y472441D03*
X364173Y740157D03*
X405511Y39370D03*
X587795Y307087D03*
X590551Y472441D03*
X612204Y606299D03*
X875984Y31496D03*
Y472441D03*
Y606299D03*
Y740157D03*
G54D33*
X81925Y554363D03*
X81924Y558398D03*
X101444Y555240D03*
X101476Y560166D03*
X129600Y626300D03*
X188200Y489000D03*
X202800Y483000D03*
X171501Y469168D03*
Y473268D03*
X174900Y526700D03*
X202246Y501509D03*
X204000Y608800D03*
X175802Y574058D03*
X202155Y625814D03*
X163100Y619900D03*
X152957Y602562D03*
X149200Y596700D03*
X207400Y638200D03*
X179434Y619120D03*
X143200Y620200D03*
X151000D03*
X244800Y543700D03*
X229757Y534556D03*
X241400Y556100D03*
Y551900D03*
X233100Y505300D03*
X259261Y548308D03*
X251000Y536200D03*
X258600Y535800D03*
X238900Y593500D03*
X231592Y622802D03*
X226400Y597200D03*
Y593200D03*
X227400Y571900D03*
X227775Y576816D03*
X227700Y585900D03*
X231400Y567000D03*
X268700Y584500D03*
X266688Y666467D03*
X215100Y642200D03*
X225492Y642006D03*
X331500Y387774D03*
X345600Y377800D03*
X324125Y558073D03*
X327985Y566198D03*
X347600Y579231D03*
X328156Y571267D03*
X309217Y682959D03*
X365680Y544200D03*
X379315Y617425D03*
X360835Y661505D03*
X497218Y42607D03*
X493650Y33781D03*
X510700Y65000D03*
X538406Y68742D03*
X704291Y484208D03*
X696800Y455000D03*
X701700Y442100D03*
X828500Y422612D03*
X814881Y403117D03*
G54D60*
X369480Y622436D03*
Y626036D03*
G54D51*
X339331Y49803D03*
X360669Y91929D03*
G54D42*
X133600Y617700D03*
X204800Y490500D03*
X212165Y486408D03*
X191694Y536028D03*
X170800Y506500D03*
X166761Y495720D03*
X211378Y535801D03*
X166737Y505554D03*
X179000Y506500D03*
X207278Y535801D03*
X162537Y505554D03*
X200031Y536194D03*
X147247Y505187D03*
X151351Y505197D03*
X158294Y505554D03*
X192471Y614338D03*
X188431Y613338D03*
X147723Y615596D03*
X217908Y483035D03*
X222100Y478600D03*
X233300Y547100D03*
X237300D03*
X246980Y561968D03*
X219473Y535573D03*
X221800Y611700D03*
X225900Y611600D03*
X273895Y571352D03*
X272900Y587700D03*
X242600Y578500D03*
X269806Y571352D03*
X330600Y509300D03*
X288286Y587255D03*
X351500Y587490D03*
X314800Y681400D03*
X357000Y590200D03*
X373400Y626000D03*
X498150Y58730D03*
X459610Y37040D03*
X493500Y67300D03*
X511500Y58200D03*
X837816Y347814D03*
X848820Y403472D03*
G54D70*
G01X361750Y522660D02*
Y523250D01*
X364000Y525500D01*
G54D16*
X65400Y546000D03*
X100619Y564385D03*
X97113Y564386D03*
X92870Y564415D03*
X78247Y562479D03*
X137100Y597000D03*
X133600D03*
X207600Y495580D03*
X327538Y600224D03*
X689875Y468836D03*
X686496Y512847D03*
X690134Y512896D03*
X693692Y512862D03*
X765453Y525125D03*
X786667Y511552D03*
X782667D03*
X760375Y525096D03*
X756375D03*
X769453Y525125D03*
X773453D03*
X790667Y511552D03*
X794667D03*
G54D34*
X140550Y503660D03*
Y501100D03*
Y498540D03*
X134050D03*
Y503660D03*
X322850Y515460D03*
Y512900D03*
Y510340D03*
X316350D03*
Y515460D03*
X337502Y594713D03*
Y592153D03*
Y589593D03*
X331002D03*
Y594713D03*
X303250Y600760D03*
Y598200D03*
Y595640D03*
X296750D03*
Y600760D03*
X365230Y534960D03*
Y532400D03*
Y529840D03*
X358730D03*
Y534960D03*
X368250Y522660D03*
Y520100D03*
Y517540D03*
X361750D03*
Y522660D03*
G54D52*
X339331Y91929D03*
X360669Y49803D03*
G54D43*
X199890Y468960D03*
Y471520D03*
Y474080D03*
Y476640D03*
X183710D03*
Y474080D03*
Y471520D03*
Y468960D03*
X310092Y575349D03*
Y577909D03*
Y580469D03*
Y583029D03*
X297292D03*
Y580469D03*
Y577909D03*
Y575349D03*
X323039Y677049D03*
Y674489D03*
Y671929D03*
Y669369D03*
Y666809D03*
Y664249D03*
Y661689D03*
X345239D03*
Y664249D03*
Y666809D03*
Y669369D03*
Y671929D03*
Y674489D03*
Y677049D03*
G54D61*
X526025Y64390D03*
X518275D03*
X522150Y71890D03*
X824116Y334544D03*
X827991Y327044D03*
X820241D03*
G54D25*
X47468Y567316D03*
X54850Y580250D03*
X102500Y712200D03*
X195371Y559210D03*
X202630Y583440D03*
X876590Y222573D03*
G54D71*
G01X74151Y545516D02*
Y547064D01*
X74910Y547823D01*
X76976D01*
X77390Y548237D01*
Y549476D01*
X76863Y550003D01*
X72497D01*
X71050Y551450D01*
X64750D01*
X63924Y552276D01*
X61982D01*
X60488Y553770D01*
X54910D01*
X53416Y552276D01*
X48295D01*
X45935Y549916D01*
Y549526D01*
G01D02*
X41971D01*
X41953Y549508D01*
G01X74498Y551757D02*
X73855Y552400D01*
X65500D01*
X64724Y553176D01*
X62966D01*
X60490Y555652D01*
X59824D01*
X58819Y556657D01*
Y560525D01*
X58319Y561025D01*
X57319D01*
X56819Y560525D01*
Y557760D01*
X55952Y556893D01*
X54587D01*
X53577Y557903D01*
X46773D01*
X45935Y557065D01*
Y555153D01*
G01D02*
X41935D01*
G01X71002Y539219D02*
X66540Y534757D01*
X63287D01*
X62787Y534257D01*
Y532317D01*
X62287Y531817D01*
X61287D01*
X60787Y532317D01*
Y534257D01*
X60287Y534757D01*
X59287D01*
X58787Y534257D01*
Y532317D01*
X58287Y531817D01*
X57287D01*
X56787Y532317D01*
Y534257D01*
X56287Y534757D01*
X55438D01*
X54696Y535499D01*
X47399D01*
X45856Y533956D01*
Y532622D01*
G01X41915Y532638D02*
X45840D01*
X45856Y532622D01*
G01X64151Y514027D02*
Y510027D01*
X64251Y509927D01*
G01X81276Y548766D02*
Y545376D01*
X76000Y540100D01*
Y535061D01*
X72337Y531398D01*
Y529015D01*
X66901Y523579D01*
Y516387D01*
X64541Y514027D01*
X64151D01*
G01X45856Y521269D02*
Y521659D01*
X48442Y524245D01*
X57237D01*
X57737Y523745D01*
Y521754D01*
X58237Y521254D01*
X59237D01*
X59737Y521754D01*
Y523745D01*
X60237Y524245D01*
X62355D01*
X74076Y535966D01*
G01X41882Y521271D02*
X45854D01*
X45856Y521269D01*
G01Y526995D02*
Y527856D01*
X47745Y529745D01*
X58156D01*
X58656Y529245D01*
Y527128D01*
X59156Y526628D01*
X60156D01*
X60656Y527128D01*
Y529245D01*
X61156Y529745D01*
X63845D01*
X71669Y537569D01*
X71686D01*
X72652Y538535D01*
Y538552D01*
X75508Y541408D01*
Y542198D01*
G01X41925Y526995D02*
X45856D01*
G01X71002Y542368D02*
X69320Y544050D01*
X58292D01*
X57533Y544809D01*
Y551250D01*
X57079Y551704D01*
X56079D01*
X55533Y551158D01*
Y547243D01*
X55033Y546743D01*
X47149D01*
X45856Y545450D01*
Y543876D01*
G01X41908Y543881D02*
X45851D01*
X45856Y543876D01*
G01X41808Y538254D02*
X45851D01*
X45856Y538249D01*
G01D02*
Y539893D01*
X46962Y540999D01*
X55625D01*
X56079Y540545D01*
Y537645D01*
X56579Y537145D01*
X57579D01*
X58079Y537645D01*
Y541555D01*
X58510Y541986D01*
X59510D01*
X60079Y541417D01*
Y537645D01*
X60579Y537145D01*
X61579D01*
X62079Y537645D01*
Y540088D01*
X62691Y540700D01*
X66371D01*
X67852Y539219D01*
G01X54206Y571795D02*
X54472Y571529D01*
X57305D01*
X57805Y571029D01*
Y567221D01*
X58305Y566721D01*
X59305D01*
X59805Y567221D01*
Y571029D01*
X60305Y571529D01*
X61343D01*
X63050Y569822D01*
G01X45935Y560879D02*
Y562704D01*
X46860Y563629D01*
X58505D01*
X58802Y563332D01*
X59510D01*
X61351Y565173D01*
X62059D01*
X62766Y564466D01*
Y563758D01*
X60925Y561917D01*
Y561209D01*
X61535Y560599D01*
Y559296D01*
X65106Y555725D01*
Y555380D01*
X67169Y553317D01*
X69352D01*
X71002Y554967D01*
G01X41850Y560900D02*
X45914D01*
X45935Y560879D01*
G01X54206Y571795D02*
Y575006D01*
X55050Y575850D01*
G01X121233Y450900D02*
X126267D01*
X135367Y460000D01*
X161800D01*
X163950Y457850D01*
X190016D01*
X191799Y456067D01*
X211829D01*
X257578Y501816D01*
X271242D01*
X280350Y510924D01*
Y520550D01*
X293800Y534000D01*
G01X136950Y479700D02*
Y483900D01*
G01D02*
Y485065D01*
X140490Y488605D01*
G01X132777Y462639D02*
X132779Y462641D01*
X162462D01*
X165253Y459850D01*
X191153D01*
X192936Y458067D01*
X210867D01*
X213126Y460326D01*
X213159D01*
G01X231476Y449662D02*
X228314Y446500D01*
X223071D01*
X215771Y439200D01*
X152791D01*
X146893Y445098D01*
X126330D01*
G01D02*
X116766D01*
X113300Y448564D01*
G01X134050Y498540D02*
Y482401D01*
X130787Y479138D01*
G01X298719Y542538D02*
X298700Y542519D01*
Y535730D01*
X281850Y518880D01*
Y510302D01*
X271864Y500316D01*
X258512D01*
X211946Y453750D01*
X163893D01*
X159143Y458500D01*
X137024D01*
X127059Y448535D01*
X118065D01*
G01X138023Y456188D02*
X159333D01*
X163271Y452250D01*
X211324D01*
X211325Y452249D01*
X212567D01*
X212568Y452250D01*
X212646D01*
X244196Y483800D01*
X272619D01*
X280587Y491768D01*
G01X75405Y514027D02*
Y509961D01*
X75373Y509929D01*
G01X86750Y542368D02*
X83555D01*
X79200Y538013D01*
Y527960D01*
X79700Y527460D01*
X81964D01*
X82464Y526960D01*
Y525960D01*
X81964Y525460D01*
X79700D01*
X79200Y524960D01*
Y524328D01*
X78155Y523283D01*
Y516387D01*
X75795Y514027D01*
X75405D01*
G01X86750Y539218D02*
Y533117D01*
X87250Y532617D01*
X88612D01*
X89112Y532117D01*
Y531117D01*
X88612Y530617D01*
X87250D01*
X86750Y530117D01*
Y529117D01*
X87250Y528617D01*
X92062D01*
X92648Y528031D01*
Y527203D01*
X92062Y526617D01*
X88111D01*
X87462Y525968D01*
Y524385D01*
X89409Y522438D01*
Y516387D01*
X87799Y514777D01*
X87409D01*
X86659Y514027D01*
G01D02*
Y510064D01*
X86673Y510050D01*
G01X69778Y514027D02*
X70528Y514777D01*
X70918D01*
X72528Y516387D01*
Y522540D01*
X76586Y526598D01*
Y528496D01*
X76086Y528996D01*
X75134D01*
X74634Y529496D01*
Y530496D01*
X75134Y530996D01*
X76086D01*
X76586Y531496D01*
Y532690D01*
X77500Y533604D01*
Y539418D01*
X83600Y545518D01*
G01X69778Y514027D02*
Y509927D01*
X69878Y509827D01*
G01X97913Y514027D02*
Y510063D01*
X97900Y510050D01*
G01X97913Y514027D02*
X98663Y514777D01*
X99053D01*
X101890Y517614D01*
Y530072D01*
X100337Y531625D01*
X95957D01*
X94250Y533332D01*
Y538250D01*
X89899Y542601D01*
Y545518D01*
G01X92286Y514027D02*
Y510063D01*
X92273Y510050D01*
G01X89899Y539218D02*
Y537664D01*
X89399Y537164D01*
X88338D01*
X87838Y536664D01*
Y535664D01*
X88338Y535164D01*
X89399D01*
X89899Y534664D01*
Y533642D01*
X95036Y528505D01*
Y527270D01*
X95536Y526770D01*
X99237D01*
X99823Y526184D01*
Y525356D01*
X99237Y524770D01*
X95536D01*
X95036Y524270D01*
Y516387D01*
X92676Y514027D01*
X92286D01*
G01X81032D02*
X81782Y514777D01*
X82172D01*
X83782Y516387D01*
Y522894D01*
X84622Y523734D01*
Y529272D01*
X84122Y529772D01*
X81449D01*
X80949Y530272D01*
Y531272D01*
X81449Y531772D01*
X84122D01*
X84622Y532272D01*
Y533272D01*
X84122Y533772D01*
X81449D01*
X80949Y534272D01*
Y535272D01*
X81449Y535772D01*
X84122D01*
X84622Y536272D01*
Y538197D01*
X83600Y539219D01*
G01X81068Y509916D02*
Y513991D01*
X81032Y514027D01*
G01X98026Y560166D02*
X95101D01*
X91158Y556223D01*
Y552411D01*
X91879Y551690D01*
X99850D01*
X100350Y551190D01*
Y550190D01*
X99850Y549690D01*
X88875D01*
X86750Y551815D01*
G01X101494Y555240D02*
Y555670D01*
X98026Y559138D01*
Y560166D01*
G01X125400Y498600D02*
X127900Y501100D01*
X140550D01*
G01X120273Y497309D02*
X124109D01*
X125400Y498600D01*
G01X116222Y497305D02*
X120269D01*
X120273Y497309D01*
G01X124903Y613900D02*
X122320D01*
X121643Y614577D01*
G01X139500Y611200D02*
X140000Y610700D01*
X140252D01*
X145750Y605202D01*
Y596700D01*
G01X139400Y615000D02*
X140804D01*
X141400Y615596D01*
X143823D01*
G01X139400Y615000D02*
X137350D01*
X136600Y614250D01*
X133600D01*
G01X154500Y629600D02*
X154065D01*
X149960Y633705D01*
X144281D01*
X143381Y634605D01*
X137850D01*
X136600Y635855D01*
Y639200D01*
X133300Y642500D01*
X102200D01*
X94227Y634527D01*
X76227D01*
X70700Y629000D01*
G01X128250Y610500D02*
X132955D01*
X133835Y609620D01*
G01X175197Y596063D02*
X176797Y597663D01*
Y612928D01*
X173704Y616021D01*
Y618024D01*
X164728Y627000D01*
X145100D01*
X142500Y629600D01*
X137000D01*
X134354Y632246D01*
G01X129850Y639000D02*
Y634900D01*
G01X134354Y632246D02*
X131700Y634900D01*
X129850D01*
G01X162500Y624850D02*
X144250D01*
X142400Y626700D01*
X134883D01*
X134483Y626300D01*
X129650D01*
G01X129850Y630800D02*
X129650Y630600D01*
Y626300D01*
G01X139774Y666686D02*
Y665432D01*
X141683Y663523D01*
X144491D01*
X147347Y666379D01*
Y675027D01*
X156860Y684540D01*
X170201D01*
X183171Y671570D01*
X244877D01*
X245665Y672358D01*
X250592D01*
X251550Y671400D01*
X275800D01*
X282150Y677750D01*
Y679067D01*
X283569Y680486D01*
X291754D01*
G01X184750Y489000D02*
Y492250D01*
X183900Y493100D01*
G01D02*
X182400D01*
X181200Y491900D01*
Y489451D01*
G01X148000Y475550D02*
Y482500D01*
X147100Y483400D01*
G01X140450Y483900D02*
X146600D01*
X147100Y483400D01*
G01X144943Y480031D02*
Y476793D01*
X143700Y475550D01*
G01X144943Y480031D02*
X142350D01*
X142019Y479700D01*
X140450D01*
G01X168051Y473268D02*
Y474151D01*
X172300Y478400D01*
G01D02*
X175514Y481614D01*
Y489214D01*
X178500Y492200D01*
G01X184230Y520045D02*
Y518033D01*
X186720Y515543D01*
Y512236D01*
X185200Y510716D01*
Y509821D01*
X183750Y508371D01*
Y499179D01*
X183751Y499178D01*
Y497522D01*
X178500Y492271D01*
Y492200D01*
G01X167999Y479200D02*
X164100Y475301D01*
Y470300D01*
X165232Y469168D01*
X168051D01*
G01X172900Y484101D02*
X167999Y479200D01*
G01X172900Y484101D02*
Y489500D01*
X181750Y498350D01*
Y508799D01*
X180964Y509585D01*
Y515641D01*
X180230Y516375D01*
Y519112D01*
X177700Y521642D01*
Y523950D01*
X174950Y526700D01*
G01X162537Y499000D02*
X159900Y496363D01*
Y489189D01*
X165218Y483871D01*
X169252D01*
G01X188250Y489000D02*
Y488006D01*
X184800Y484556D01*
G01X214808Y463300D02*
X212800D01*
X209810Y460310D01*
X199990D01*
X194540Y465760D01*
X183950D01*
X180040Y461850D01*
X167321D01*
X164071Y465100D01*
X154334D01*
G01D02*
Y472984D01*
X158850Y477500D01*
Y485900D01*
X155900Y488850D01*
Y491200D01*
X153600Y493500D01*
Y497500D01*
X155500Y499400D01*
Y506500D01*
X163000Y514000D01*
X163950D01*
X167000Y517050D01*
G01X149000Y494500D02*
Y488600D01*
G01X204800Y487050D02*
X202150D01*
X201600Y486500D01*
G01X200250Y489500D02*
Y488550D01*
X198200Y486500D01*
G01X199890Y471520D02*
X207300D01*
G01D02*
X209523D01*
X210000Y471043D01*
X212118D01*
G01X208400Y476900D02*
X205580Y474080D01*
X199890D01*
G01X217908Y479585D02*
X211085D01*
X208400Y476900D01*
G01X199890Y476640D02*
Y478990D01*
X202850Y481950D01*
Y483000D01*
G01X207500D02*
X202850D01*
G01X207500D02*
X212123D01*
X212165Y482958D01*
G01X178600Y483800D02*
Y476400D01*
X180920Y474080D01*
X183710D01*
G01X176252Y473571D02*
X171854D01*
X171551Y473268D01*
G01X176252Y473571D02*
X178129D01*
X180180Y471520D01*
X183710D01*
G01X176224Y468472D02*
X178731D01*
X179219Y468960D01*
X183710D01*
G01X176224Y468472D02*
X174480D01*
X173784Y469168D01*
X171551D01*
G01X192300Y490050D02*
Y487784D01*
X190036Y485520D01*
G01X378840Y448690D02*
X378050Y447900D01*
X375930D01*
X374775Y446745D01*
X352755D01*
X347959Y451541D01*
X302233D01*
X290874Y462900D01*
X250396D01*
X250133Y462637D01*
X241748D01*
X227111Y448000D01*
X222052D01*
X215102Y441050D01*
X163681D01*
X163031Y441700D01*
G01X152589Y486031D02*
Y482459D01*
X153489Y481559D01*
G01X152589Y489531D02*
Y491111D01*
X151500Y492200D01*
Y498600D01*
X153489Y500589D01*
Y507444D01*
X152600Y508333D01*
Y521500D01*
X154400Y523300D01*
Y524400D01*
G01X140985Y454250D02*
X159149D01*
X162649Y450750D01*
X210702D01*
X210703Y450749D01*
X213189D01*
X213190Y450750D01*
X213268D01*
X244118Y481600D01*
X277700D01*
X280700Y484600D01*
G01X370800Y554700D02*
X374117Y551383D01*
Y544698D01*
X379850Y538965D01*
Y508092D01*
X371750Y499992D01*
Y494603D01*
X363820Y486673D01*
X338283D01*
X325265Y499691D01*
X301744D01*
X282153Y480100D01*
X253644D01*
X245744Y472200D01*
X236840D01*
X213340Y448700D01*
X174036D01*
G01X148490Y451286D02*
X149675Y452471D01*
X158806D01*
X162577Y448700D01*
X174036D01*
G01X383080Y554897D02*
Y553980D01*
X382550Y553450D01*
Y542631D01*
X384350Y540831D01*
Y506226D01*
X376250Y498126D01*
Y496469D01*
X376251Y496468D01*
Y495226D01*
X376252Y495225D01*
Y492739D01*
X365686Y482173D01*
X336417D01*
X323399Y495191D01*
X304591D01*
X279300Y469900D01*
X257800D01*
X256700Y471000D01*
X251424D01*
X248061Y467637D01*
X239567D01*
X214480Y442550D01*
X165159D01*
X164059Y443650D01*
X152746D01*
X151016Y445380D01*
G01D02*
Y445573D01*
X144245Y452344D01*
G01X384347Y558647D02*
X383447D01*
X381050Y556250D01*
Y542009D01*
X382850Y540209D01*
Y506848D01*
X374750Y498748D01*
Y495847D01*
X374751Y495846D01*
Y494604D01*
X374752Y494603D01*
Y493361D01*
X365064Y483673D01*
X337039D01*
X324021Y496691D01*
X303969D01*
X281715Y474437D01*
X252225D01*
X246988Y469200D01*
X239008D01*
X214408Y444600D01*
X181938D01*
G01X151877Y450439D02*
X157166Y445150D01*
X165643D01*
X166193Y444600D01*
X181938D01*
G01X382922Y561735D02*
X379550Y558363D01*
Y541387D01*
X381350Y539587D01*
Y507470D01*
X373250Y499370D01*
Y495225D01*
X373251Y495224D01*
Y493982D01*
X364442Y485173D01*
X337661D01*
X324643Y498191D01*
X302366D01*
X282775Y478600D01*
X254266D01*
X246366Y470700D01*
X237462D01*
X213412Y446650D01*
X190999D01*
G01D02*
X159666D01*
X155877Y450439D01*
G01X145000Y488600D02*
Y492200D01*
G01X147247Y501737D02*
Y497230D01*
X145000Y494983D01*
Y492200D01*
G01X192300Y493550D02*
X188088D01*
X187964Y493426D01*
G01D02*
Y496050D01*
X188834Y496920D01*
G01X203356Y495487D02*
X204800Y494043D01*
Y490550D01*
G01X197847Y494417D02*
Y490597D01*
X196750Y489500D01*
G01X166737Y505604D02*
Y509697D01*
X167680Y510640D01*
G01X166761Y495770D02*
Y498900D01*
G01Y495770D02*
X171519D01*
X171780Y496031D01*
G01X162700Y495750D02*
X166741D01*
X166761Y495770D01*
G01X166737Y502104D02*
Y498924D01*
X166761Y498900D01*
G01X202380Y567970D02*
X201750Y567340D01*
Y564080D01*
X200910Y563240D01*
G01X196890Y563850D02*
X197500Y563240D01*
X200910D01*
G01X160999Y556501D02*
Y568599D01*
X161716Y569316D01*
X163241D01*
X164198Y570273D01*
Y572921D01*
X164179Y572940D01*
G01X164018Y553518D02*
X166391D01*
X167345Y554472D01*
Y568357D01*
X168255Y569267D01*
X170447D01*
X172047Y570867D01*
G01X164148Y556148D02*
Y568360D01*
X165104Y569316D01*
X166391D01*
X167298Y570223D01*
Y572738D01*
X167500Y572940D01*
G01X190945Y545669D02*
X190089D01*
X187699Y543279D01*
G01X187288Y536101D02*
Y542868D01*
X187699Y543279D01*
G01X203610Y529397D02*
X204324D01*
X207278Y532351D01*
G01X172047Y545669D02*
X173597Y547219D01*
Y549597D01*
X174371Y550371D01*
X183071D01*
X184700Y552000D01*
G01X175200Y555000D02*
X175077D01*
X172047Y551970D01*
G01X159449Y545671D02*
X157857Y544079D01*
X151109D01*
X149824Y542794D01*
G01X160157Y537164D02*
X161049Y538056D01*
Y544119D01*
X162599Y545669D01*
G01X170597Y539852D02*
X170448Y540001D01*
Y543162D01*
X169491Y544119D01*
X167299D01*
X165749Y545669D01*
G01X187800Y547278D02*
X186257Y548821D01*
X184646D01*
G01X187800Y547278D02*
Y546300D01*
X185569Y544069D01*
X183925D01*
X183046Y543190D01*
Y541241D01*
X180690Y538885D01*
Y535299D01*
X183670Y532319D01*
Y531816D01*
G01X178200Y540400D02*
Y543331D01*
X179896Y545027D01*
Y546596D01*
X180521Y547221D01*
X183096D01*
X184646Y545671D01*
G01X178200Y540400D02*
Y533050D01*
X179400Y531850D01*
G01X182964Y510414D02*
Y511309D01*
X184720Y513065D01*
Y514714D01*
X182230Y517204D01*
Y519941D01*
X179700Y522471D01*
Y524800D01*
X179400Y525100D01*
G01X209627Y540605D02*
Y540773D01*
X207880Y542520D01*
X206693D01*
G01X209627Y540605D02*
Y538200D01*
X207278Y535851D01*
G01X156299Y545671D02*
X156023Y545947D01*
X149775D01*
X145367Y541539D01*
Y533700D01*
X146700Y532367D01*
Y530150D01*
G01Y526650D02*
X151250D01*
X154400Y529800D01*
Y533500D01*
G01X184230Y520045D02*
Y520770D01*
X181700Y523300D01*
Y526346D01*
X183670Y528316D01*
G01X179400Y528350D02*
X176600D01*
X174950Y526700D01*
G01X162537Y499000D02*
Y502104D01*
G01X158294Y505604D02*
X162537D01*
G01X160286Y508429D02*
X162257Y510400D01*
X163300D01*
G01D02*
X164400Y509300D01*
Y507467D01*
X162537Y505604D01*
G01X175197Y545671D02*
X173647Y544121D01*
Y537751D01*
X174930Y536468D01*
Y534600D01*
G01D02*
Y530720D01*
X174950Y530700D01*
G01X164784Y539407D02*
Y540334D01*
X162599Y542519D01*
G01X163300Y530650D02*
X164784Y532134D01*
Y539407D01*
G01X167454Y530927D02*
X167000Y531381D01*
Y535500D01*
G01D02*
Y540621D01*
X168898Y542519D01*
G01X158200Y532900D02*
Y531000D01*
X158600Y530600D01*
Y528450D01*
G01X158200Y532900D02*
Y535500D01*
X158000Y535700D01*
Y540820D01*
X156299Y542521D01*
G01X194094Y542519D02*
X192527D01*
X190936Y540928D01*
G01D02*
Y538864D01*
X191694Y538106D01*
Y536078D01*
G01X174900Y506550D02*
X170800D01*
G01D02*
Y509440D01*
X171200Y509840D01*
G01X170800Y503050D02*
Y499800D01*
G01X167000Y520550D02*
Y522400D01*
X166600Y522800D01*
Y524100D01*
G01X167000Y520550D02*
X164262D01*
X164000Y520812D01*
X160339D01*
G01X151351Y501747D02*
X149000Y499396D01*
Y494500D01*
G01X174636Y513171D02*
Y512864D01*
X176900Y510600D01*
Y496500D01*
G01X177600Y517400D02*
X178136Y516864D01*
Y513171D01*
G01X174717Y524010D02*
Y522583D01*
X175700Y521600D01*
Y520813D01*
X177600Y518913D01*
Y517400D01*
G01X179000Y506550D02*
Y509112D01*
X178898Y509214D01*
Y509764D01*
X178869Y509793D01*
G01X156501Y564317D02*
Y568441D01*
X157360Y569300D01*
X160077D01*
X161643Y570866D01*
X162598D01*
G01X202296Y501509D02*
Y499508D01*
X200650Y497862D01*
G01X198796Y505657D02*
Y501509D01*
G01X199501Y509275D02*
Y509201D01*
X198796Y508496D01*
Y505657D01*
G01X224000Y539130D02*
X223130Y540000D01*
X216467D01*
X214541Y541926D01*
Y543162D01*
X213634Y544069D01*
X212399D01*
X211392Y545076D01*
Y546312D01*
X210483Y547221D01*
X201991D01*
X200393Y548819D01*
G01X211378Y535851D02*
Y538100D01*
X211700Y538422D01*
Y541300D01*
X209842Y543158D01*
Y545669D01*
G01X215448Y535651D02*
X211578D01*
X211378Y535851D01*
G01X209842Y564567D02*
X211400Y563009D01*
Y560816D01*
X212349Y559867D01*
X213635D01*
X213637Y559869D01*
X216784D01*
X216915Y560000D01*
X222487D01*
X225500Y556987D01*
G01X209842Y558268D02*
X208242Y556668D01*
Y554477D01*
X207335Y553570D01*
X206049D01*
X205092Y552613D01*
Y551327D01*
X204185Y550420D01*
X199801D01*
X198381Y549000D01*
X197400D01*
G01X158294Y502104D02*
Y499294D01*
X158000Y499000D01*
G01X214040Y504230D02*
X209618D01*
X208148Y505700D01*
X207612D01*
X207500Y505812D01*
G01X196013Y536225D02*
X196736D01*
X200400Y539889D01*
Y542167D01*
X200402Y542169D01*
G01D02*
X200400Y542171D01*
Y545662D01*
X200393Y545669D01*
G01X196013Y532725D02*
Y529637D01*
X197150Y528500D01*
G01X200200Y529200D02*
X199500Y528500D01*
X197150D01*
G01X200031Y532744D02*
X203440D01*
X203696Y533000D01*
G01X203930Y540283D02*
Y542909D01*
X206692Y545671D01*
G01X203930Y540283D02*
Y540143D01*
X200031Y536244D01*
G01X156200Y535800D02*
X156100Y535700D01*
Y532000D01*
X156700Y531400D01*
Y528500D01*
X154400Y526200D01*
Y524400D01*
G01X236074Y536841D02*
X232959D01*
X229400Y540400D01*
X227726D01*
X226026Y542100D01*
X221903D01*
X217692Y546311D01*
Y546312D01*
X216785Y547219D01*
X211758D01*
X210158Y548819D01*
X209842D01*
G01X147247Y505237D02*
X145317D01*
X143740Y503660D01*
X140550D01*
G01X151351Y505247D02*
X149209D01*
X149199Y505237D01*
X147247D01*
G01X150553Y509389D02*
Y512500D01*
G01X146600Y520750D02*
Y522290D01*
X148050Y523740D01*
G01X203356Y495487D02*
X200313D01*
X197938Y497862D01*
X196800D01*
G01X193200Y497000D02*
X194350Y495850D01*
X196414D01*
X197847Y494417D01*
G01X211750Y634500D02*
Y627340D01*
X213400Y625690D01*
Y621100D01*
G01X211750Y638400D02*
Y634500D01*
G01X213400Y621100D02*
Y617488D01*
X214688Y616200D01*
Y607803D01*
X212656Y605771D01*
X211661D01*
X206692Y600802D01*
Y596063D01*
G01X203450Y592912D02*
X204498D01*
X206049Y594463D01*
X207285D01*
X208242Y595420D01*
Y601079D01*
X212033Y604870D01*
X213028D01*
X215061Y606903D01*
X215062D01*
X215588Y607429D01*
Y607430D01*
X215646Y607488D01*
Y614736D01*
X216188Y615278D01*
Y616822D01*
X215646Y617364D01*
Y622646D01*
X219466Y626466D01*
Y628146D01*
G01X213201Y570843D02*
X211257D01*
X209841Y572259D01*
Y574016D01*
G01X206692D02*
X205092Y572416D01*
Y570223D01*
X204185Y569316D01*
X203726D01*
X202380Y567970D01*
G01X197620Y636210D02*
Y630707D01*
X197611Y630698D01*
G01X190154Y636190D02*
Y633846D01*
X193400Y630600D01*
G01X184932Y601225D02*
Y602710D01*
X187952Y605730D01*
Y609409D01*
X188431Y609888D01*
G01X192471Y610888D02*
X189431D01*
X188431Y609888D01*
G01X184932Y601225D02*
X186945Y599212D01*
X187796D01*
G01X184400Y607850D02*
Y603451D01*
X182982Y602033D01*
Y601782D01*
X181586Y600386D01*
Y599123D01*
G01X180571Y611325D02*
Y612188D01*
X182298Y613915D01*
Y615326D01*
X184660Y617688D01*
G01X184400Y607850D02*
X182298D01*
X180571Y609577D01*
Y611325D01*
G01X206900Y577100D02*
X208291Y578491D01*
Y580958D01*
X209198Y581865D01*
X211391D01*
X212991Y583465D01*
G01X207820Y570860D02*
X208291Y571331D01*
Y574659D01*
X209050Y575418D01*
Y576374D01*
X209841Y577165D01*
G01X343372Y655836D02*
X340436D01*
X330900Y646300D01*
X281754D01*
X274816Y639362D01*
X259686D01*
X248548Y650500D01*
X243271D01*
X241821Y651950D01*
X206925D01*
X206325Y652550D01*
X204341D01*
X203841Y653050D01*
X191277D01*
X179150Y640923D01*
Y635450D01*
X177200Y633500D01*
G01X174799Y630303D02*
Y631099D01*
X177200Y633500D01*
G01X347013Y656090D02*
X343979Y659124D01*
X340524D01*
X329900Y648500D01*
X280936D01*
X273798Y641362D01*
X260515D01*
X249377Y652500D01*
X244100D01*
X242650Y653950D01*
X212050D01*
X209750Y656250D01*
X190732D01*
X177232Y642750D01*
X176250D01*
X174850Y641350D01*
Y636045D01*
X172449Y633644D01*
G01X171400Y630200D02*
Y632595D01*
X172449Y633644D01*
G01X156500Y598500D02*
X155500Y599500D01*
X154500D01*
X153007Y600993D01*
Y602562D01*
G01X156500Y598500D02*
X158937Y596063D01*
X159448D01*
G01X190944Y602362D02*
Y605862D01*
G01D02*
X192932Y607850D01*
X196500D01*
G01X199950Y614000D02*
Y617600D01*
G01D02*
Y618681D01*
X196087Y622544D01*
X194718D01*
G01X195500Y618000D02*
X196100Y617400D01*
Y614050D01*
G01X196500Y611350D02*
Y613650D01*
X196100Y614050D01*
G01X200500Y622000D02*
X198705Y623795D01*
Y625814D01*
G01D02*
X194948D01*
X194718Y626044D01*
G01X200500Y622000D02*
X202450Y620050D01*
Y615550D01*
X203900Y614100D01*
G01X203542Y596063D02*
X201943Y597662D01*
Y602947D01*
X201993Y602997D01*
Y603005D01*
X202900Y603912D01*
X204112D01*
X205750Y605550D01*
Y615650D01*
X204950Y616450D01*
Y622750D01*
X206800Y624600D01*
Y627047D01*
G01D02*
Y629900D01*
X205050Y631650D01*
X201750D01*
X200100Y633300D01*
G01X207450Y634400D02*
Y632300D01*
X209000Y630750D01*
Y623800D01*
X207450Y622250D01*
Y622000D01*
G01Y638200D02*
Y634400D01*
G01Y622000D02*
Y615992D01*
X209193Y614249D01*
G01X208423Y605303D02*
X211570Y608450D01*
X212500D01*
G01X208423Y605303D02*
X205142Y602022D01*
Y595470D01*
X204185Y594513D01*
X193187D01*
X192500Y595200D01*
Y597619D01*
X194094Y599213D01*
G01X168898Y596063D02*
Y597020D01*
X167298Y598620D01*
Y599856D01*
X166771Y600383D01*
Y612529D01*
X165000Y614300D01*
G01X163150Y619900D02*
Y616150D01*
X165000Y614300D01*
G01X159650Y619900D02*
Y617386D01*
X161047Y615989D01*
G01X162750Y612217D02*
Y614286D01*
X161047Y615989D01*
G01X216141Y599212D02*
X215212D01*
X210463Y594463D01*
X209198D01*
X208291Y593556D01*
Y591791D01*
X206692Y590192D01*
Y589763D01*
G01X168898Y592913D02*
Y593870D01*
X167348Y595420D01*
Y596656D01*
X166391Y597613D01*
X165155D01*
X164198Y598570D01*
Y601766D01*
X160088Y605876D01*
Y608100D01*
G01D02*
Y608812D01*
X155778Y613122D01*
X155341D01*
G01X159500Y612300D02*
X162600Y609200D01*
X164400D01*
G01X159500Y612300D02*
Y612463D01*
X155341Y616622D01*
G01X153000Y594927D02*
X153796Y594131D01*
X158473D01*
X158805Y594463D01*
X160998D01*
X162598Y596063D01*
G01X153000Y594927D02*
X151227Y596700D01*
X149250D01*
G01X194093Y592913D02*
Y589764D01*
G01X215900Y595500D02*
X214757Y594357D01*
Y592483D01*
X213636Y591362D01*
X209248D01*
X208267Y590381D01*
Y588839D01*
X206692Y587264D01*
Y586614D01*
G01X232536Y588078D02*
X230814Y589800D01*
X218372D01*
X216784Y588212D01*
X211441D01*
X209842Y586613D01*
G01X226195Y603279D02*
X226032D01*
X220353Y597600D01*
X215242D01*
X210664Y593022D01*
X209950D01*
X209841Y592913D01*
G01X144263Y609023D02*
X144986Y608300D01*
X147100D01*
X148400Y607000D01*
G01X149507Y602562D02*
Y605893D01*
X148400Y607000D01*
G01X178346Y596064D02*
X180095Y594315D01*
X183515D01*
X184800Y595600D01*
X186800D01*
G01X178347Y599213D02*
Y601647D01*
X179500Y602800D01*
G01X163991Y606162D02*
X165748Y604405D01*
Y599213D01*
G01X169242Y603107D02*
Y600852D01*
X168898Y600508D01*
Y599213D01*
G01X154903Y608458D02*
X155364D01*
X162598Y601224D01*
Y599213D01*
G01X157800Y602900D02*
X159448Y601252D01*
Y599213D01*
G01X169021Y610228D02*
X169121Y610128D01*
Y606379D01*
X171751Y603749D01*
Y601203D01*
X170498Y599950D01*
Y597613D01*
X172048Y596063D01*
G01X194120Y636210D02*
X195650Y637840D01*
Y642800D01*
G01X186654Y636190D02*
Y638054D01*
X187650Y639050D01*
Y640467D01*
X187795Y640612D01*
Y642681D01*
G01X175984Y619120D02*
Y615485D01*
X177732Y613737D01*
Y609121D01*
X179344Y607509D01*
G01X181500Y595900D02*
X179900Y597500D01*
Y600159D01*
X181800Y602059D01*
Y605053D01*
X179344Y607509D01*
G01X143823Y615596D02*
X147673D01*
X147723Y615646D01*
G01X151800Y610300D02*
Y612000D01*
X148154Y615646D01*
X147723D01*
G01X197264Y596849D02*
X198030D01*
X200393Y599212D01*
G01X151750Y590500D02*
X153310D01*
X154820Y592010D01*
X155950D01*
G01X181530Y592765D02*
X180166D01*
X178715Y591314D01*
X158700D01*
X158004Y592010D01*
X155950D01*
G01X181530Y592765D02*
X182985D01*
X184700Y591050D01*
G01X162500Y624850D02*
X164756D01*
X172104Y617502D01*
Y615358D01*
X175197Y612265D01*
Y599213D01*
G01X143250Y620200D02*
X147550D01*
G01X173247Y607000D02*
X173500Y606747D01*
Y600665D01*
X172048Y599213D01*
G01X173247Y607000D02*
X172450Y607797D01*
Y613450D01*
X170604Y615296D01*
Y616880D01*
X164684Y622800D01*
X150150D01*
X147550Y620200D01*
G01X211650Y642200D02*
Y638500D01*
X211750Y638400D01*
G01X207450Y638200D02*
X207050Y638600D01*
Y642300D01*
G01X195650Y642800D02*
Y643050D01*
X193750Y644950D01*
Y646767D01*
X196033Y649050D01*
X202183D01*
X202683Y648550D01*
X204667D01*
X205267Y647950D01*
X240163D01*
X241613Y646500D01*
X246500D01*
X250900Y642100D01*
G01X187795Y642681D02*
Y643641D01*
X195204Y651050D01*
X203012D01*
X203512Y650550D01*
X205496D01*
X206096Y649950D01*
X240992D01*
X242442Y648500D01*
X247719D01*
X258857Y637362D01*
X261635D01*
X264800Y634197D01*
Y632300D01*
G01X297330Y682986D02*
X282533D01*
X279650Y680103D01*
Y678786D01*
X274764Y673900D01*
X252586D01*
X251628Y674858D01*
X244552D01*
X243764Y674070D01*
X184207D01*
X171043Y687234D01*
X155971D01*
X143235Y674498D01*
Y666647D01*
X143174Y666586D01*
G01X228475Y484151D02*
Y482400D01*
X226475Y480400D01*
G01X267670Y485870D02*
X269088Y487288D01*
Y493288D01*
X276165Y500365D01*
X277509D01*
X287003Y509859D01*
X290590D01*
G01X271100Y485900D02*
Y492471D01*
X275884Y497255D01*
X279654D01*
G01X294720Y182200D02*
X292270Y184650D01*
Y381848D01*
X303458Y393036D01*
X317597D01*
X319961Y395400D01*
X322722D01*
X330227Y402905D01*
Y424983D01*
X324700Y430510D01*
X322905D01*
X321615Y431800D01*
X319689D01*
X316448Y435041D01*
X295393D01*
X292273Y438161D01*
X264057D01*
X263537Y438681D01*
X246019D01*
X241700Y443000D01*
X232172D01*
X230672Y441500D01*
X225300D01*
X222995Y443805D01*
G01X680300Y17500D02*
X680283D01*
X669833Y7050D01*
X355760D01*
X324350Y38460D01*
Y126140D01*
X332032Y133822D01*
Y163368D01*
X318650Y176750D01*
X293953D01*
X290770Y179933D01*
Y382470D01*
X302836Y394536D01*
X316975D01*
X319339Y396900D01*
X322100D01*
X328727Y403527D01*
Y424361D01*
X324078Y429010D01*
X322283D01*
X320993Y430300D01*
X319067D01*
X315826Y433541D01*
X294771D01*
X291712Y436600D01*
X245200D01*
X240900Y440900D01*
G01X216250Y471100D02*
X216093Y471043D01*
X212118D01*
G01X217908Y479585D02*
X221165D01*
X222100Y478650D01*
G01X339507Y433648D02*
X331614Y441541D01*
X298088D01*
X288629Y451000D01*
X278300D01*
X274937Y447637D01*
X271221D01*
X268458Y450400D01*
X259929D01*
X259029Y449500D01*
X251742D01*
X245874Y455368D01*
Y458478D01*
G01X242500Y458900D02*
X244237Y460637D01*
X250962D01*
X251225Y460900D01*
X290045D01*
X301404Y449541D01*
X340925D01*
X351597Y438869D01*
G01X253400Y453500D02*
X256900Y457000D01*
X291116D01*
X300575Y447541D01*
X337159D01*
X354158Y430542D01*
Y430400D01*
G01X273400Y449700D02*
X276700Y453000D01*
X289458D01*
X298917Y443541D01*
X332884D01*
X359200Y417225D01*
Y380195D01*
X363586Y375809D01*
G01X363701Y379208D02*
X361700Y381209D01*
Y417554D01*
X333713Y445541D01*
X299746D01*
X290287Y455000D01*
X261700D01*
X258200Y451500D01*
X252571D01*
X249465Y454606D01*
Y458000D01*
G01X370763Y547900D02*
X371117Y547546D01*
Y543454D01*
X376850Y537721D01*
Y528465D01*
X376849Y528464D01*
Y509335D01*
X368750Y501236D01*
Y495847D01*
X362576Y489673D01*
X339527D01*
X326509Y502691D01*
X295808D01*
X292617Y499500D01*
X288319D01*
X280587Y491768D01*
G01X280700Y484600D02*
X297291Y501191D01*
X325887D01*
X338905Y488173D01*
X363198D01*
X370250Y495225D01*
Y500614D01*
X378349Y508713D01*
Y527842D01*
X378350Y527843D01*
Y538343D01*
X372617Y544076D01*
Y549483D01*
X370800Y551300D01*
G01X225532Y450047D02*
X240622Y465137D01*
X249097D01*
X249360Y465400D01*
X279700D01*
X306991Y492691D01*
X322363D01*
X339926Y475128D01*
X361013D01*
G01X239100Y450500D02*
X239118D01*
X242118Y447500D01*
X259858D01*
X260658Y448300D01*
X267729D01*
X271729Y444300D01*
X292500D01*
X297259Y439541D01*
X330559D01*
X354100Y416000D01*
Y381483D01*
X349867Y377250D01*
X348000D01*
X347450Y377800D01*
X345650D01*
G01X237600Y455500D02*
Y452018D01*
X239100Y450518D01*
Y450500D01*
G01X218500Y490750D02*
X221737D01*
X223146Y489341D01*
G01X218500Y490750D02*
Y493500D01*
X216600Y495400D01*
Y504230D01*
G01X223146Y489341D02*
X224975Y487512D01*
Y484151D01*
G01X294720Y178600D02*
X297400Y181280D01*
Y188100D01*
X295525Y189975D01*
Y377547D01*
X301978Y384000D01*
X312805D01*
X321205Y392400D01*
X323966D01*
X333227Y401661D01*
Y426227D01*
X325944Y433510D01*
X324149D01*
X322859Y434800D01*
X320933D01*
X317692Y438041D01*
X296637D01*
X292107Y442571D01*
X274844D01*
X274843Y442572D01*
X267435D01*
G01D02*
X264758D01*
X261330Y446000D01*
X229936D01*
X227994Y444058D01*
X226607D01*
G01X294720Y185600D02*
X293770Y186550D01*
Y381226D01*
X304080Y391536D01*
X318219D01*
X320583Y393900D01*
X323344D01*
X331727Y402283D01*
Y425605D01*
X325322Y432010D01*
X323527D01*
X322237Y433300D01*
X320311D01*
X317070Y436541D01*
X296015D01*
X292386Y440170D01*
X264170D01*
X260740Y443600D01*
X245800D01*
G01D02*
X244900Y444500D01*
X231055D01*
X230610Y444055D01*
G01X219700Y563100D02*
X217610D01*
X216141Y564569D01*
G01X235002Y562120D02*
X232904D01*
X232134Y561350D01*
X230766D01*
X229250Y562866D01*
Y563684D01*
X228284Y564650D01*
X222501D01*
X221901Y565250D01*
X218294D01*
X216141Y567403D01*
Y567718D01*
G01X235002Y562120D02*
X237448D01*
X237849Y562521D01*
X239470D01*
G01X269709Y560363D02*
X264285D01*
X260513Y564135D01*
G01X265231Y570631D02*
Y562431D01*
X265100Y562300D01*
G01X224600Y560900D02*
X216660D01*
X216141Y561419D01*
G01X237950Y551900D02*
X234236Y555614D01*
X230936D01*
X227025Y559525D01*
X225975D01*
X224600Y560900D01*
G01X227600Y563000D02*
Y560365D01*
X228644Y559321D01*
X230277D01*
G01D02*
X234729D01*
X237950Y556100D01*
G01X219503Y528088D02*
Y532093D01*
X219473Y532123D01*
G01X219503Y528088D02*
X222912D01*
X223750Y527250D01*
X227867D01*
X229717Y525400D01*
X242300D01*
X243808Y523892D01*
X248459D01*
G01X212991Y542519D02*
Y540442D01*
X214235Y539198D01*
G01D02*
X214933Y538500D01*
X216596D01*
X219473Y535623D01*
G01X244850Y543700D02*
X246400Y545250D01*
Y547900D01*
G01X244850Y543700D02*
Y540150D01*
G01X246400Y547900D02*
Y549900D01*
X244400Y551900D01*
X241450D01*
G01X248950Y543600D02*
Y546700D01*
X248521Y547129D01*
Y551079D01*
X246463Y553137D01*
G01D02*
X243500Y556100D01*
X241450D01*
G01X248700Y540000D02*
X248950Y540250D01*
Y543600D01*
G01X224900Y497730D02*
X219160D01*
G01X224900D02*
X226670D01*
X228200Y496200D01*
G01X260000Y517300D02*
Y513761D01*
X246039Y499800D01*
X230971D01*
X226357Y504414D01*
Y504514D01*
G01X263600Y540700D02*
X263900D01*
X266150Y538450D01*
Y528750D01*
X260000Y522600D01*
Y517300D01*
G01X297292Y583029D02*
X299629D01*
X300600Y584000D01*
X303700D01*
X305911Y581789D01*
Y574734D01*
X308575Y572070D01*
Y567462D01*
X314008Y562029D01*
Y550471D01*
X317351Y547128D01*
Y530765D01*
X316550Y529964D01*
Y529944D01*
X294271Y507665D01*
X287658D01*
X283200Y503207D01*
Y500801D01*
X279654Y497255D01*
G01X242970Y562521D02*
X246477D01*
X246980Y562018D01*
G01X279000Y555000D02*
X276154Y552154D01*
X265531D01*
X260435Y557250D01*
X254629D01*
X249861Y562018D01*
X246980D01*
G01X279000Y555000D02*
X292006Y568006D01*
Y574797D01*
G01X289800Y569182D02*
X274772Y554154D01*
X266360D01*
X261264Y559250D01*
X256450D01*
X252500Y563200D01*
G01D02*
X249450Y566250D01*
Y567100D01*
G01X229807Y534556D02*
Y530200D01*
G01D02*
X225200D01*
X223800Y531600D01*
G01X226307Y534556D02*
Y536823D01*
X224000Y539130D01*
G01X236400Y502150D02*
Y504500D01*
X235600Y505300D01*
X233150D01*
G01X225500Y556987D02*
X225887Y556600D01*
X228500D01*
X231708Y553392D01*
Y550997D01*
X233300Y549405D01*
Y547150D01*
G01X237300D02*
X233300D01*
G01X225500Y557000D02*
Y556987D01*
G01X221700Y545500D02*
X220418D01*
X218618Y547300D01*
X218600D01*
X217080Y548820D01*
X216142D01*
G01X216141Y555120D02*
X218866D01*
X219236Y554750D01*
X222050D01*
X224300Y552500D01*
G01X220500Y557800D02*
X220031Y558269D01*
X216141D01*
G01X258300Y504750D02*
X255095D01*
X248645Y498300D01*
X229954D01*
X223910Y504344D01*
Y504897D01*
X221427Y507380D01*
X214623D01*
X214040Y506797D01*
Y504230D01*
G01X275100Y509800D02*
X270050Y504750D01*
X258300D01*
G01X255811Y548308D02*
Y552211D01*
X256500Y552900D01*
G01X260900Y553900D02*
X257500D01*
X256500Y552900D01*
G01X236260Y529177D02*
Y531340D01*
X228907Y538693D01*
X227707D01*
X225200Y541200D01*
X220177D01*
X219946Y540969D01*
X218648D01*
X217741Y541876D01*
Y543112D01*
X216784Y544069D01*
X215549D01*
X214110Y545508D01*
X213153D01*
X212992Y545669D01*
G01X286400Y569200D02*
X281061Y563861D01*
X273809D01*
G01D02*
X269209D01*
X269709Y563863D01*
G01X257600Y543400D02*
Y541400D01*
X255800Y539600D01*
G01D02*
Y536450D01*
X255150Y535800D01*
G01X251050Y536200D02*
X254750D01*
X255150Y535800D01*
G01X222058Y637894D02*
X222069Y637883D01*
Y634188D01*
G01D02*
X222019D01*
X219466Y631635D01*
Y628146D01*
G01X216141Y580315D02*
X217979D01*
X219375Y581711D01*
G01X224098Y581666D02*
X224053Y581711D01*
X219375D01*
G01X232896Y613795D02*
X244650Y602041D01*
Y601733D01*
X245733Y600650D01*
X246041D01*
X251100Y595591D01*
Y595000D01*
G01X260705Y598359D02*
X257346Y595000D01*
X251100D01*
G01X216141Y577165D02*
X216458D01*
X217264Y576359D01*
X219638D01*
G01X224325Y576816D02*
X220095D01*
X219638Y576359D01*
G01X227950Y567000D02*
X223292D01*
G01D02*
X221042D01*
X220209Y566167D01*
X218650D01*
X217743Y567074D01*
Y568309D01*
X216784Y569268D01*
X215300D01*
X213750Y567718D01*
X212991D01*
G01X213201Y570843D02*
X220843D01*
X221900Y571900D01*
X223950D01*
G01X219688Y587096D02*
X218588Y585996D01*
Y585912D01*
X216141Y583465D01*
G01X219688Y587096D02*
X221104D01*
X222300Y585900D01*
X224250D01*
G01X345386Y604896D02*
Y604913D01*
X342718Y607581D01*
X332655D01*
X329836Y610400D01*
X288329D01*
X270696Y592767D01*
X244933D01*
X243900Y593800D01*
X242333D01*
G01X236400Y568800D02*
X234150D01*
X233800Y569150D01*
X220726D01*
X219293Y567717D01*
G01X236400Y568800D02*
X239312D01*
X241380Y566732D01*
G01X269806Y571402D02*
X266002D01*
X265231Y570631D01*
G01X212991Y574016D02*
X214541Y575566D01*
X216784D01*
X218712Y573638D01*
X220450D01*
X221463Y574651D01*
X231385D01*
X235284Y578550D01*
X237500D01*
G01D02*
X242600D01*
G01X216141Y574016D02*
X217751Y572406D01*
X220910D01*
X222255Y573751D01*
X232841D01*
X233387Y574297D01*
X236800D01*
G01D02*
X238415D01*
X241680Y571032D01*
G01X219000Y617500D02*
X218200Y616700D01*
Y609500D01*
G01X212991Y599212D02*
X212992Y599213D01*
Y602363D01*
G01X221800Y608250D02*
X221550D01*
X218300Y605000D01*
G01D02*
X216107Y602807D01*
X213436D01*
X212992Y602363D01*
G01X225900Y608150D02*
Y605905D01*
X221895Y601900D01*
X221000D01*
G01D02*
X218829D01*
X216141Y599212D01*
G01X244880Y566732D02*
X245248Y567100D01*
X249450D01*
G01X222950Y597200D02*
Y593200D01*
G01X215900Y595500D02*
X219136D01*
X221436Y593200D01*
X222950D01*
G01X238100Y586450D02*
X234164D01*
X232536Y588078D01*
G01X242100Y586450D02*
X238100D01*
G01X235450Y593500D02*
X233865D01*
X231815Y591450D01*
X220250D01*
X219951Y591749D01*
X218298D01*
G01X238950Y597500D02*
Y597000D01*
X235450Y593500D01*
G01X218298Y591749D02*
X215935D01*
X213950Y589764D01*
X212992D01*
G01X226195Y603279D02*
X228011Y605095D01*
Y614361D01*
X227612Y614760D01*
Y616588D01*
X227013Y617187D01*
X227012Y617404D01*
Y619930D01*
X227013Y619931D01*
Y619932D01*
X228142Y621061D01*
Y622802D01*
G01X224000Y622750D02*
X228090D01*
X228142Y622802D01*
G01X272900Y584250D02*
Y580873D01*
X273022Y580751D01*
G01X272900Y584250D02*
X270812D01*
X270562Y584500D01*
X268750D01*
G01Y588500D02*
Y584500D01*
G01X268200Y578700D02*
X266300D01*
X264750Y580250D01*
G01D02*
Y584000D01*
X265250Y584500D01*
G01X256007Y575050D02*
X254500D01*
X252300Y577250D01*
G01X247400Y576400D02*
X248250Y577250D01*
X252300D01*
G01X242600Y575050D02*
X246050D01*
X247400Y576400D01*
G01X249450Y571100D02*
X249382Y571032D01*
X245180D01*
G01X264200Y574100D02*
X263607Y574693D01*
X260096D01*
G01D02*
X259208D01*
X257266Y572751D01*
X254369D01*
X254270Y572850D01*
X250850D01*
X249450Y571450D01*
Y571100D01*
G01X261810Y633980D02*
X260428Y635362D01*
X257638D01*
X250900Y642100D01*
G01X273895Y567902D02*
X269806D01*
G01X273895D02*
X274902D01*
X279500Y572500D01*
Y574700D01*
X281510Y576710D01*
Y583003D01*
G01X222042Y642006D02*
X222058Y641990D01*
Y637894D01*
G01X271220Y679910D02*
X274000Y682690D01*
Y684013D01*
X278507Y688520D01*
X322405D01*
X323772Y687153D01*
Y687152D01*
X325332Y685592D01*
G01X250128Y678106D02*
X251922Y679900D01*
X255000D01*
G01X235042Y656173D02*
X244527D01*
X246200Y654500D01*
X252212D01*
X263500Y643212D01*
G01X243100Y677500D02*
X248732Y683132D01*
X257478D01*
X268895Y694549D01*
Y696648D01*
X267100Y698443D01*
Y699700D01*
G01X266738Y666467D02*
X266238Y665967D01*
Y662362D01*
X266400Y662200D01*
G01X335100Y237500D02*
Y233080D01*
X335098Y233078D01*
G01X335100Y237500D02*
Y239100D01*
X333800Y240400D01*
X315308D01*
X305782Y230874D01*
G01X334198Y248824D02*
X329835Y244461D01*
X312800D01*
G01D02*
X305454D01*
G01X305373Y251101D02*
X306274Y250200D01*
X321000D01*
X321800Y249400D01*
X321900D01*
G01D02*
X326500D01*
X329478Y252378D01*
X334282D01*
G01X324600Y252600D02*
X324500Y252500D01*
X308251D01*
X306412Y254339D01*
G01X334260Y255820D02*
X327820D01*
X324600Y252600D01*
G01X305781Y241076D02*
X297025Y249832D01*
Y376925D01*
X302600Y382500D01*
X313427D01*
X321827Y390900D01*
X324588D01*
X334728Y401040D01*
Y433250D01*
X329937Y438041D01*
X324341D01*
X322950Y436650D01*
X321700D01*
G01X330806Y392324D02*
X336756D01*
G01X330806D02*
X328992D01*
X328050Y391382D01*
Y387774D01*
G01D02*
Y387724D01*
X323926Y383600D01*
X323900D01*
X320874Y380574D01*
X303900D01*
G01X339507Y433648D02*
X357000Y416155D01*
Y378105D01*
X359550Y375555D01*
Y372504D01*
X359323Y372277D01*
G01X345650Y377800D02*
X345600Y377850D01*
Y379855D01*
X343412Y382043D01*
X342662D01*
X340631Y384074D01*
Y384824D01*
G01X339300Y526300D02*
Y524900D01*
X337212Y522812D01*
Y519008D01*
X341773Y514447D01*
Y503799D01*
X346887Y498685D01*
Y496095D01*
X344688Y493896D01*
G01X351597Y438869D02*
X366490Y423976D01*
Y385399D01*
X363699Y382608D01*
G01X354158Y430400D02*
X363852Y420706D01*
Y386157D01*
X363703Y386008D01*
G01X293800Y534000D02*
X296254Y536454D01*
Y546706D01*
G01X286011Y553256D02*
Y557451D01*
X285833Y557629D01*
G01X365230Y532400D02*
X353916D01*
Y532359D01*
X346040Y524483D01*
Y518667D01*
X351120Y513587D01*
X351132D01*
X351250Y513469D01*
Y503295D01*
X354300Y500245D01*
G01X290590Y509859D02*
X293616D01*
X315337Y531580D01*
Y546293D01*
X312007Y549623D01*
Y561201D01*
X306575Y566633D01*
Y571241D01*
X303911Y573905D01*
Y577515D01*
X300957Y580469D01*
X297292D01*
G01X341400Y560050D02*
X343465Y557985D01*
Y535382D01*
X338581Y530498D01*
X336880D01*
Y530496D01*
X336881D01*
G01X341615Y556015D02*
X341465Y555865D01*
Y540470D01*
X336953Y535958D01*
Y534506D01*
G01X331900Y561752D02*
Y549700D01*
G01X331806Y561752D02*
X331900D01*
G01X328035Y566198D02*
X330436D01*
X331900Y564734D01*
Y561752D01*
G01X324175Y558073D02*
X326508D01*
X328012Y556569D01*
G01X329050Y552315D02*
Y555531D01*
X328012Y556569D01*
G01X320675Y558073D02*
Y563504D01*
X318970Y565209D01*
G01X315893Y567721D02*
X316458D01*
X318970Y565209D01*
G01X337600Y515500D02*
Y513700D01*
X339773Y511527D01*
Y502823D01*
X344755Y497841D01*
G01X341558Y567689D02*
X339116Y565247D01*
Y540950D01*
X334596Y536430D01*
Y518504D01*
X337600Y515500D01*
G01X339300Y526300D02*
Y528388D01*
X345465Y534553D01*
Y559584D01*
X341349Y563700D01*
Y563750D01*
G01X310092Y575349D02*
Y573382D01*
X310575Y572899D01*
Y568291D01*
X316757Y562109D01*
Y550551D01*
X324000Y543308D01*
Y539400D01*
X328200Y535200D01*
X330200D01*
G01X357853Y500825D02*
X353750Y504928D01*
Y514505D01*
X352168Y516087D01*
X352156D01*
X348540Y519703D01*
Y523440D01*
X354940Y529840D01*
X358730D01*
G01X296680Y556314D02*
Y561013D01*
X296570Y561123D01*
G01D02*
Y562327D01*
X293970Y564927D01*
G01X335000Y500600D02*
X331560D01*
X331240Y500920D01*
G01X330600Y505850D02*
Y501560D01*
X331240Y500920D01*
G01X330600Y509350D02*
Y511000D01*
X331600Y512000D01*
Y512900D01*
G01D02*
X331245Y513255D01*
X329055D01*
X328700Y512900D01*
X322850D01*
G01X334900Y557600D02*
Y551565D01*
X334811Y551476D01*
G01X328206Y571267D02*
X330624D01*
X334900Y566991D01*
Y557600D01*
G01X311900Y511500D02*
X313060Y510340D01*
X316350D01*
G01X360980Y590436D02*
Y593020D01*
X359500Y594500D01*
X355799D01*
X345403Y604896D01*
X345386D01*
G01X357000Y590250D02*
X353115Y594135D01*
X352716D01*
G01X347650Y574900D02*
X350683D01*
X350746Y574837D01*
G01X347650Y574900D02*
Y579231D01*
G01X303000Y586800D02*
Y588400D01*
X308572Y593972D01*
X313718D01*
X322237Y602491D01*
X323413D01*
G01X331002Y589593D02*
X328198D01*
X326682Y591109D01*
X324994D01*
X323012Y593091D01*
Y599638D01*
X323413Y600039D01*
Y602491D01*
G01X303000Y586800D02*
X302900Y586900D01*
X297291D01*
X296310Y587881D01*
Y593339D01*
X296750Y593779D01*
Y595640D01*
G01X297292Y580469D02*
X293028D01*
X292853Y580644D01*
X290825D01*
X289951Y579770D01*
X288286D01*
G01X297292Y583029D02*
X293771D01*
X292995Y583805D01*
X288286D01*
G01X315616Y571817D02*
X315831Y571602D01*
X317477D01*
X319401Y569678D01*
G01D02*
X321563Y567516D01*
Y567486D01*
X322851Y566198D01*
X324535D01*
G01X352716Y590535D02*
X350729Y592522D01*
Y596363D01*
X347398Y599694D01*
G01D02*
X341511Y605581D01*
X331826D01*
X330243Y607164D01*
X318953D01*
X318072Y606283D01*
G01X309765Y603750D02*
X308250D01*
X305260Y600760D01*
X303250D01*
G01X309765Y608200D02*
X312655D01*
X314572Y606283D01*
G01X309765Y608200D02*
Y603750D01*
G01X351500Y584040D02*
X347853D01*
X347784Y584109D01*
G01X337502Y592153D02*
X343162D01*
X344102Y591213D01*
G01D02*
Y586074D01*
X341377Y583349D01*
X336923D01*
G01X337502Y594713D02*
X344102D01*
G01D02*
X345709D01*
X348161Y592261D01*
G01X351500Y587540D02*
Y588922D01*
X348161Y592261D01*
G01X309765Y600250D02*
X308419D01*
X306369Y598200D01*
X303250D01*
G01X309765Y600250D02*
Y598115D01*
X307650Y596000D01*
G01X315315Y575204D02*
X318417D01*
X319831Y573790D01*
G01X324706Y571267D02*
X322354D01*
X319831Y573790D01*
G01X310092Y580469D02*
X317813D01*
G01X310092Y583029D02*
X315873D01*
X317813Y584969D01*
G01X345239Y671929D02*
X349771D01*
X353404Y668296D01*
X365994D01*
X367472Y669774D01*
X373276D01*
X375550Y667500D01*
X378616D01*
X384466Y661650D01*
G01X357385Y661505D02*
X351195D01*
X348451Y664249D01*
X345239D01*
G01X352600Y674489D02*
X345239D01*
G01X357483Y673696D02*
X353393D01*
X352600Y674489D01*
G01X345239Y669369D02*
X342631D01*
X341000Y671000D01*
Y675400D01*
X342649Y677049D01*
X345239D01*
G01X357655Y677695D02*
X354750D01*
X352557Y679888D01*
G01D02*
X350254D01*
X347415Y677049D01*
X345239D01*
G01X317159Y667813D02*
X319110D01*
X320666Y669369D01*
X323039D01*
G01X317159Y667813D02*
X316316Y668656D01*
Y670412D01*
X317516Y671612D01*
G01X315000Y674900D02*
X313465D01*
X311798Y673233D01*
G01X312000Y666750D02*
Y669098D01*
X311798Y669300D01*
Y673233D01*
G01X338135Y670511D02*
X336158Y672488D01*
Y674767D01*
X327432Y683493D01*
X327431D01*
X325332Y685592D01*
G01X312000Y663250D02*
X316550D01*
G01D02*
X318450D01*
X319449Y664249D01*
X323039D01*
G01X357350Y665580D02*
X350829D01*
X349600Y666809D01*
X345239D01*
G01X323039Y674489D02*
X329670D01*
X330604Y673555D01*
Y671030D01*
X330593Y671019D01*
G01D02*
Y668793D01*
X328609Y666809D01*
X323039D01*
G01X303741Y654095D02*
Y652379D01*
X305551Y650569D01*
X326638D01*
X327368Y651299D01*
G01D02*
X329989Y653920D01*
G01X314800Y677950D02*
X315650D01*
X317500Y676100D01*
Y675267D01*
X320838Y671929D01*
X323039D01*
G01X309267Y682959D02*
Y678783D01*
X310100Y677950D01*
G01D02*
X314800D01*
G01X297330Y682986D02*
X305740D01*
X305767Y682959D01*
G01X323039Y661689D02*
X320489D01*
X317300Y658500D01*
X313000D01*
G01X307849Y665450D02*
Y661301D01*
X307850Y661300D01*
G01X313000Y658500D02*
X310650D01*
X307850Y661300D01*
G01X307849Y668950D02*
Y675351D01*
X302714Y680486D01*
X291754D01*
G01X462874Y95922D02*
Y94572D01*
X452702Y84400D01*
X440600D01*
X425765Y69565D01*
Y56265D01*
G01X398000Y165400D02*
Y171600D01*
X396562Y173038D01*
Y294138D01*
X366140Y324560D01*
Y360840D01*
X382900Y377600D01*
Y452400D01*
X375900Y459400D01*
Y463976D01*
X373576Y466300D01*
G01X398050Y162000D02*
X395800Y164250D01*
Y170800D01*
X394562Y172038D01*
Y293309D01*
X364140Y323731D01*
Y361669D01*
X380900Y378429D01*
Y451300D01*
X373530Y458670D01*
Y462826D01*
X373534Y462830D01*
G01X392100Y683900D02*
X394400Y681600D01*
Y656281D01*
X400350Y650331D01*
Y532250D01*
X399700Y531600D01*
Y362600D01*
X381009Y343909D01*
G01X392000Y679800D02*
X392400Y679400D01*
Y655452D01*
X398350Y649502D01*
Y541249D01*
X394979Y537878D01*
Y506321D01*
X397700Y503600D01*
Y364204D01*
X380799Y347303D01*
G01X373700Y329700D02*
X376000Y332000D01*
Y334200D01*
X401700Y359900D01*
Y520282D01*
X402350Y520932D01*
Y651160D01*
X396400Y657110D01*
Y659800D01*
G01X373700Y482700D02*
X373220Y482220D01*
Y477980D01*
X378200Y473000D01*
Y462500D01*
X384900Y455800D01*
Y374300D01*
X377000Y366400D01*
Y366078D01*
X376910D01*
G01X381276Y469106D02*
X381370D01*
Y472569D01*
X380837Y473102D01*
Y479700D01*
X376817Y483720D01*
Y491182D01*
X380837Y495202D01*
Y497937D01*
X383700Y500800D01*
G01X384400Y545195D02*
X385850Y543745D01*
Y505604D01*
X383700Y503454D01*
Y500800D01*
G01X361750Y517540D02*
Y505216D01*
X362701Y504265D01*
X362666D01*
G01X385700Y586100D02*
Y583376D01*
X381130Y578806D01*
Y565794D01*
X376617Y561281D01*
Y544817D01*
G01X358120Y547654D02*
Y549249D01*
X357379Y549990D01*
Y552518D01*
G01X362280Y554590D02*
X362040Y554350D01*
X357879D01*
X357379Y553850D01*
Y552518D01*
G01X365730Y544200D02*
Y541050D01*
G01X362500Y499970D02*
X358600Y503870D01*
Y518651D01*
X360109Y520160D01*
X363941D01*
X366441Y522660D01*
X368250D01*
G01D02*
X373540D01*
X374040Y523160D01*
Y529592D01*
X368672Y534960D01*
X365230D01*
G01X365730Y544200D02*
Y551390D01*
G01D02*
Y555170D01*
X363450Y557450D01*
Y559625D01*
G01X365730Y541050D02*
Y539570D01*
X365230Y539070D01*
Y534960D01*
G01X357853Y500825D02*
X360558Y498120D01*
X363267D01*
X365001Y499854D01*
Y502394D01*
X367607Y505000D01*
X368900D01*
G01X372494Y513020D02*
X374086Y514612D01*
Y517383D01*
G01D02*
X374049D01*
G01X374086D02*
Y519511D01*
X373497Y520100D01*
X368250D01*
G01X357500Y563450D02*
X356700Y562650D01*
Y560200D01*
X357400Y559500D01*
G01X370950Y563500D02*
X367350D01*
X366490Y564360D01*
G01D02*
X363760D01*
X358900Y559500D01*
X357400D01*
G01X372900Y538700D02*
X372335D01*
X368300Y542735D01*
Y556500D01*
X376676Y564876D01*
Y568400D01*
G01X360980Y590436D02*
X363800D01*
X364300Y590936D01*
Y592900D01*
G01X379365Y617425D02*
X383575D01*
X384500Y616500D01*
G01X361792Y625652D02*
Y629735D01*
X361227Y630300D01*
G01X380000Y598350D02*
Y596400D01*
X378400Y594800D01*
G01X373400Y622550D02*
X376944D01*
X377714Y621780D01*
G01D02*
X383313D01*
G01X375000Y573200D02*
Y572036D01*
X373529Y570565D01*
X366141D01*
X365953Y570753D01*
G01D02*
X365750Y570956D01*
Y574900D01*
G01X375000Y573200D02*
X373650Y574550D01*
X369800D01*
G01X378965Y610613D02*
X380987D01*
X382600Y609000D01*
G01X385700Y586100D02*
Y589028D01*
X387848Y591176D01*
Y612579D01*
X389050Y613781D01*
Y624050D01*
X383666Y629434D01*
Y660850D01*
X384466Y661650D01*
G01X376676Y568400D02*
Y570176D01*
X378568Y572068D01*
Y585568D01*
X385348Y592348D01*
Y613615D01*
X386550Y614817D01*
Y623014D01*
X381166Y628398D01*
Y628834D01*
X381117Y628883D01*
Y661393D01*
X378505Y664005D01*
X367295D01*
X365720Y665580D01*
X360850D01*
G01X378832Y659705D02*
X377395D01*
X375595Y661505D01*
X360885D01*
G01X360983Y673696D02*
X361704D01*
X364600Y670800D01*
G01X357655Y681195D02*
X360900D01*
X361914Y680181D01*
G01X396400Y659800D02*
Y687200D01*
X393400Y690200D01*
Y702113D01*
X392079Y703434D01*
G01X498150Y58780D02*
X501720D01*
X502300Y58200D01*
G01X493500Y59500D02*
X496750D01*
X497470Y58780D01*
X498150D01*
G01X493500Y63850D02*
X489505D01*
X488800Y63145D01*
Y62100D01*
G01D02*
Y60287D01*
X489587Y59500D01*
X493500D01*
G01X490210Y37883D02*
X489610Y38483D01*
X486417D01*
X486400Y38500D01*
G01X467016Y20430D02*
Y21966D01*
X467429Y22379D01*
Y25800D01*
G01X461710Y25990D02*
X463960D01*
X464150Y25800D01*
X467429D01*
G01X461710Y25990D02*
Y29440D01*
X461350Y29800D01*
G01X459610Y33590D02*
Y31540D01*
X461350Y29800D01*
G01X441450Y37800D02*
Y42532D01*
X442003Y43085D01*
X443859D01*
X443869Y43095D01*
G01X450454Y38147D02*
X450007Y37700D01*
X446403D01*
G01X443869Y43095D02*
X443879Y43085D01*
X445789D01*
X446403Y42471D01*
Y37700D01*
G01X488974Y44580D02*
X491795D01*
X493768Y42607D01*
G01X488974Y44580D02*
X486980D01*
X486527Y44127D01*
Y41939D01*
G01X447233Y48829D02*
X442128D01*
X437950Y44651D01*
Y37800D01*
G01X458210Y25990D02*
X452490Y31710D01*
Y64240D01*
G01X490200Y33781D02*
X489381D01*
X486700Y31100D01*
G01X483091Y33900D02*
X481193D01*
X480912Y33619D01*
X477343D01*
G01X486700Y31100D02*
X483900Y33900D01*
X483091D01*
G01X457585Y70015D02*
X455200Y67630D01*
Y43910D01*
X459610Y39500D01*
Y37090D01*
G01X480538Y112071D02*
Y110738D01*
X474608Y104808D01*
Y98058D01*
X452490Y75940D01*
Y64240D01*
G01X457585Y70015D02*
X468669Y81100D01*
X514300D01*
X515330Y82130D01*
X521330D01*
G01X515500Y59000D02*
X514750Y58250D01*
X511500D01*
G01D02*
X510250Y59500D01*
X506500D01*
G01X502400Y64400D02*
Y63600D01*
X506500Y59500D01*
G01X534956Y68742D02*
Y62900D01*
G01D02*
Y61056D01*
X532500Y58600D01*
G01X507250Y65000D02*
X503000D01*
X502400Y64400D01*
G01X521340Y77700D02*
Y82120D01*
X521330Y82130D01*
G01X522150Y71890D02*
Y76890D01*
X521340Y77700D01*
G01X534956Y68742D02*
X530377D01*
X526025Y64390D01*
G01X642998Y127863D02*
X679558Y164423D01*
Y269866D01*
X700313Y290621D01*
Y374167D01*
X706049Y379903D01*
X713994D01*
X717087Y382996D01*
Y386487D01*
X718300Y387700D01*
G01X642574Y131843D02*
X644149D01*
X677558Y165252D01*
Y270695D01*
X698313Y291450D01*
Y374996D01*
X705220Y381903D01*
X713165D01*
X715087Y383825D01*
Y385813D01*
X713200Y387700D01*
G01X675903Y29541D02*
Y31391D01*
X676436Y31924D01*
Y63595D01*
X668531Y71500D01*
G01X701183Y453339D02*
X701671Y453827D01*
Y455236D01*
X700330Y456577D01*
Y460886D01*
G01X704836Y453339D02*
X703689Y454486D01*
Y456047D01*
X702890Y456846D01*
Y460886D01*
G01X698651Y428165D02*
X689635D01*
X677810Y439990D01*
Y458086D01*
X660457Y475439D01*
Y514330D01*
X656846Y517941D01*
Y521702D01*
G01X701750Y442100D02*
X704300D01*
X705450Y440950D01*
G01X700330Y473686D02*
Y479653D01*
X699794Y480189D01*
G01D02*
X698892Y481091D01*
Y489593D01*
X700689Y491390D01*
G01D02*
X702799Y493500D01*
X705700D01*
G01X708367Y491000D02*
X707307D01*
X704486Y488179D01*
G01X700841Y484208D02*
Y484534D01*
X704486Y488179D01*
G01X700841Y484208D02*
Y482887D01*
X702890Y480838D01*
Y473686D01*
G01X759342Y543603D02*
X757551D01*
X755029Y541081D01*
Y538718D01*
G01X759255Y538797D02*
X755108D01*
X755029Y538718D01*
G01X766744Y540231D02*
Y537818D01*
X765935Y537009D01*
G01X762755Y538797D02*
Y543291D01*
X764254Y544790D01*
G01X766744Y540231D02*
Y543543D01*
X765497Y544790D01*
X764254D01*
G01X834116Y330314D02*
Y328113D01*
X833047Y327044D01*
X827991D01*
G01X827989Y340820D02*
Y337741D01*
X834116Y331614D01*
Y330314D01*
G01X824116Y334544D02*
X815186D01*
X813916Y335814D01*
Y338614D01*
G01X815016Y345064D02*
Y339714D01*
X813916Y338614D01*
G01X820766Y346339D02*
X817741D01*
X816466Y345064D01*
X815016D01*
G01X816868Y409837D02*
Y406832D01*
X818800Y404900D01*
Y403500D01*
X821800Y400500D01*
G01X819428Y409837D02*
Y407272D01*
X821700Y405000D01*
Y403900D01*
G01X835820Y380672D02*
Y375472D01*
X842916Y368376D01*
Y357214D01*
G01X835820Y380672D02*
Y394148D01*
X849420Y407748D01*
G01X819100Y390150D02*
X822150D01*
X822300Y390000D01*
G01X825000Y428800D02*
Y446532D01*
X801200Y470332D01*
Y489500D01*
X803300Y491600D01*
G01X816868Y422637D02*
Y428243D01*
X816946Y428321D01*
G01X825000Y428800D02*
X817425D01*
X816946Y428321D01*
G01X806888Y491398D02*
X803200Y487710D01*
Y471161D01*
X827000Y447361D01*
Y433000D01*
X829700Y430300D01*
Y426800D01*
G01X819428Y422637D02*
X825025D01*
X825050Y422612D01*
G01X829700Y426800D02*
X828400Y425500D01*
X825500D01*
X825050Y425050D01*
Y422612D01*
G54D26*
X64350Y582500D03*
X129100Y602100D03*
X141189Y601337D03*
X148840Y555135D03*
X153495Y555166D03*
X213000Y522800D03*
X245100Y635800D03*
X354000Y637700D03*
X349200D03*
X377714Y627580D03*
X375600Y604200D03*
G54D17*
X65400Y549600D03*
X78247Y566079D03*
X137100Y600600D03*
X133600D03*
X100619Y567985D03*
X97113Y567986D03*
X92870Y568015D03*
X207600Y499180D03*
X327538Y603824D03*
X689875Y472436D03*
X686496Y516447D03*
X690134Y516496D03*
X693692Y516462D03*
X765453Y528725D03*
X786667Y515152D03*
X782667D03*
X760375Y528696D03*
X756375D03*
X769453Y528725D03*
X773453D03*
X790667Y515152D03*
X794667D03*
G54D53*
X340631Y384824D03*
X336756Y392324D03*
X344506D03*
G54D62*
X695210Y460886D03*
X697770D03*
X700330D03*
X702890D03*
Y473686D03*
X700330D03*
X697770D03*
X695210D03*
X811748Y409837D03*
X814308D03*
X816868D03*
X819428D03*
Y422637D03*
X816868D03*
X814308D03*
X811748D03*
G54D35*
X105474Y535824D03*
X91800Y677300D03*
X181148Y568251D03*
X192089Y582625D03*
X291811Y553256D03*
X866286Y159490D03*
X878598Y391533D03*
G54D44*
X178600Y483800D03*
G54D72*
G01X-9023Y-84471D02*
X-8149Y-83596D01*
X-7494Y-82138D01*
X-7057Y-80095D01*
X-7494Y-78346D01*
X-8367Y-77179D01*
X-9896Y-76304D01*
X-15791D01*
Y-93804D01*
X-8586D01*
X-7057Y-92638D01*
X-6184Y-90887D01*
X-5747Y-88846D01*
X-6184Y-86804D01*
X-7494Y-85054D01*
X-9023Y-84471D01*
X-15791D01*
G01X3674Y-93804D02*
Y-82138D01*
G01Y-84471D02*
X4766Y-83304D01*
X5858Y-82429D01*
X7386Y-82138D01*
X8477Y-82429D01*
X9788Y-83304D01*
G01X19646Y-99054D02*
X20956Y-99637D01*
X22703Y-99054D01*
X23794Y-97888D01*
X24668Y-96429D01*
X25977Y-91763D01*
X28816Y-82138D01*
G01X21829D02*
X25977Y-91763D01*
G01X45224Y-83596D02*
X43696Y-82429D01*
X42386Y-82138D01*
X40639Y-82721D01*
X39329Y-83887D01*
X38456Y-85929D01*
X38237Y-87971D01*
X38456Y-90013D01*
X39329Y-91763D01*
X40639Y-93221D01*
X42386Y-93804D01*
X43914Y-93221D01*
X45224Y-92054D01*
G01X55956Y-85929D02*
X62943D01*
X62288Y-83887D01*
X61196Y-82721D01*
X59668Y-82138D01*
X58139Y-82429D01*
X56829Y-83304D01*
X55956Y-85346D01*
X55519Y-87096D01*
Y-88846D01*
X55956Y-90596D01*
X57048Y-92346D01*
X58358Y-93512D01*
X59886Y-93804D01*
X61414Y-93221D01*
X62943Y-91471D01*
G01X99034Y-77763D02*
X97724Y-76887D01*
X96196Y-76304D01*
X94449D01*
X92484Y-77179D01*
X90956Y-78637D01*
X89864Y-80388D01*
X88991Y-83304D01*
X88772Y-85929D01*
X89209Y-88554D01*
X89864Y-90304D01*
X91174Y-92054D01*
X92703Y-93221D01*
X94231Y-93804D01*
X95759D01*
X97288Y-93221D01*
X98598Y-92346D01*
X99690Y-91180D01*
G01X115661Y-93804D02*
Y-82138D01*
G01Y-84179D02*
X114788Y-83013D01*
X113477Y-82429D01*
X111949Y-82138D01*
X110421Y-82721D01*
X109111Y-83887D01*
X108237Y-85637D01*
X107801Y-87971D01*
X108237Y-90304D01*
X109111Y-92054D01*
X110421Y-93221D01*
X111949Y-93804D01*
X113477Y-93512D01*
X114788Y-92638D01*
X115661Y-91471D01*
G01X125519Y-93804D02*
Y-82138D01*
G01Y-85054D02*
X126393Y-83596D01*
X127703Y-82429D01*
X129449Y-82138D01*
X130977Y-82429D01*
X132288Y-83596D01*
X132943Y-85637D01*
Y-93804D01*
G01X142146Y-99054D02*
X143456Y-99637D01*
X145203Y-99054D01*
X146294Y-97888D01*
X147168Y-96429D01*
X148477Y-91763D01*
X151316Y-82138D01*
G01X144329D02*
X148477Y-91763D01*
G01X164231Y-93804D02*
X162921Y-93512D01*
X161611Y-92346D01*
X160737Y-90304D01*
X160301Y-87971D01*
X160737Y-85637D01*
X161611Y-83596D01*
X162921Y-82429D01*
X164231Y-82138D01*
X165541Y-82429D01*
X166851Y-83596D01*
X167724Y-85637D01*
X167943Y-87971D01*
X167724Y-90304D01*
X166851Y-92346D01*
X165541Y-93512D01*
X164231Y-93804D01*
G01X178019D02*
Y-82138D01*
G01Y-85054D02*
X178893Y-83596D01*
X180203Y-82429D01*
X181949Y-82138D01*
X183477Y-82429D01*
X184788Y-83596D01*
X185443Y-85637D01*
Y-93804D01*
G01X214111Y-76304D02*
X219351D01*
G01X216731D02*
Y-93804D01*
G01X214111D02*
X219351D01*
G01X234231D02*
X232484Y-93512D01*
X230956Y-92346D01*
X229646Y-90596D01*
X228772Y-88554D01*
X228336Y-86221D01*
Y-83887D01*
X228772Y-81554D01*
X229646Y-79512D01*
X230956Y-77763D01*
X232484Y-76596D01*
X234231Y-76304D01*
X235977Y-76596D01*
X237506Y-77763D01*
X238816Y-79512D01*
X239690Y-81554D01*
X240126Y-83887D01*
Y-86221D01*
X239690Y-88554D01*
X238816Y-90596D01*
X237506Y-92346D01*
X235977Y-93512D01*
X234231Y-93804D01*
G01X246054D02*
Y-76304D01*
X251731Y-90887D01*
X257408Y-76304D01*
Y-93804D01*
G01X285639Y-99637D02*
X283456Y-96721D01*
X282364Y-93804D01*
Y-82138D01*
X283456Y-79221D01*
X285639Y-76304D01*
G01X298554Y-93804D02*
Y-76304D01*
X304231Y-90887D01*
X309908Y-76304D01*
Y-93804D01*
G01X321731Y-94387D02*
X321294Y-94096D01*
Y-93512D01*
X321731Y-93221D01*
X322168Y-93512D01*
Y-94096D01*
X321731Y-94387D01*
G01X335083Y-79221D02*
X336393Y-77471D01*
X337921Y-76596D01*
X339668Y-76304D01*
X341851Y-76887D01*
X343379Y-78346D01*
X343816Y-80095D01*
X343598Y-81846D01*
X342724Y-83304D01*
X338358Y-86221D01*
X336393Y-88262D01*
X335083Y-91180D01*
X334646Y-93804D01*
X343816D01*
G01X374231D02*
X372921Y-93512D01*
X371611Y-92346D01*
X370737Y-90304D01*
X370301Y-87971D01*
X370737Y-85637D01*
X371611Y-83596D01*
X372921Y-82429D01*
X374231Y-82138D01*
X375541Y-82429D01*
X376851Y-83596D01*
X377724Y-85637D01*
X377943Y-87971D01*
X377724Y-90304D01*
X376851Y-92346D01*
X375541Y-93512D01*
X374231Y-93804D01*
G01X388019D02*
Y-82138D01*
G01Y-85054D02*
X388893Y-83596D01*
X390203Y-82429D01*
X391949Y-82138D01*
X393477Y-82429D01*
X394788Y-83596D01*
X395443Y-85637D01*
Y-93804D01*
G01X409231D02*
Y-76304D01*
G01X422146Y-99054D02*
X423456Y-99637D01*
X425203Y-99054D01*
X426294Y-97888D01*
X427168Y-96429D01*
X428477Y-91763D01*
X431316Y-82138D01*
G01X424329D02*
X428477Y-91763D01*
G01X445323Y-99637D02*
X447506Y-96721D01*
X448598Y-93804D01*
Y-82138D01*
X447506Y-79221D01*
X445323Y-76304D01*
G01X176054Y-48804D02*
Y-31304D01*
X181731Y-45887D01*
X187408Y-31304D01*
Y-48804D01*
G01X199231D02*
X197921Y-48512D01*
X196611Y-47346D01*
X195737Y-45304D01*
X195301Y-42971D01*
X195737Y-40637D01*
X196611Y-38596D01*
X197921Y-37429D01*
X199231Y-37138D01*
X200541Y-37429D01*
X201851Y-38596D01*
X202724Y-40637D01*
X202943Y-42971D01*
X202724Y-45304D01*
X201851Y-47346D01*
X200541Y-48512D01*
X199231Y-48804D01*
G01X220661Y-31304D02*
Y-48804D01*
G01Y-46180D02*
X219788Y-47638D01*
X218477Y-48512D01*
X216949Y-48804D01*
X215203Y-48221D01*
X213893Y-46763D01*
X213019Y-45013D01*
X212801Y-42971D01*
X213019Y-40929D01*
X213893Y-39179D01*
X215203Y-37721D01*
X216949Y-37138D01*
X218477Y-37429D01*
X219569Y-38013D01*
X220661Y-39179D01*
G01X230956Y-40929D02*
X237943D01*
X237288Y-38887D01*
X236196Y-37721D01*
X234668Y-37138D01*
X233139Y-37429D01*
X231829Y-38304D01*
X230956Y-40346D01*
X230519Y-42096D01*
Y-43846D01*
X230956Y-45596D01*
X232048Y-47346D01*
X233358Y-48512D01*
X234886Y-48804D01*
X236414Y-48221D01*
X237943Y-46471D01*
G01X251731Y-48804D02*
Y-31304D01*
G01X504231Y-93804D02*
Y-76304D01*
X501611Y-79804D01*
G01Y-93804D02*
X506851D01*
G01X517583Y-86513D02*
X519111Y-84471D01*
X520421Y-83304D01*
X522168Y-82721D01*
X523696Y-83304D01*
X524788Y-84471D01*
X525661Y-86221D01*
X525879Y-88262D01*
X525661Y-90013D01*
X524788Y-91763D01*
X523477Y-93221D01*
X521949Y-93804D01*
X520203Y-93221D01*
X518674Y-91471D01*
X517801Y-88846D01*
X517583Y-85929D01*
X518019Y-82138D01*
X518674Y-80095D01*
X519766Y-78054D01*
X521294Y-76596D01*
X522823Y-76304D01*
X524351Y-76887D01*
X525443Y-78346D01*
G01X534428Y-90304D02*
X535737Y-92346D01*
X537484Y-93512D01*
X539449Y-93804D01*
X541196Y-93512D01*
X542943Y-92054D01*
X544034Y-90304D01*
X544253Y-88554D01*
X543816Y-86513D01*
X542288Y-85054D01*
X540759Y-84471D01*
X538794D01*
G01X540759D02*
X542069Y-83596D01*
X543161Y-82138D01*
X543598Y-80388D01*
X543161Y-78637D01*
X542069Y-77179D01*
X540104Y-76304D01*
X538139Y-76596D01*
X536174Y-77763D01*
G01X559351Y-93804D02*
Y-76304D01*
X551272Y-88846D01*
X562190D01*
G01X570083Y-79221D02*
X571393Y-77471D01*
X572921Y-76596D01*
X574668Y-76304D01*
X576851Y-76887D01*
X578379Y-78346D01*
X578816Y-80095D01*
X578598Y-81846D01*
X577724Y-83304D01*
X573358Y-86221D01*
X571393Y-88262D01*
X570083Y-91180D01*
X569646Y-93804D01*
X578816D01*
G01X491114Y-48804D02*
Y-31304D01*
X496354D01*
X498101Y-32179D01*
X499411Y-34221D01*
X499848Y-36554D01*
X499411Y-38887D01*
X498319Y-40637D01*
X496354Y-41513D01*
X491114D01*
G01X517784Y-32763D02*
X516474Y-31887D01*
X514946Y-31304D01*
X513199D01*
X511234Y-32179D01*
X509706Y-33637D01*
X508614Y-35388D01*
X507741Y-38304D01*
X507522Y-40929D01*
X507959Y-43554D01*
X508614Y-45304D01*
X509924Y-47054D01*
X511453Y-48221D01*
X512981Y-48804D01*
X514509D01*
X516038Y-48221D01*
X517348Y-47346D01*
X518440Y-46180D01*
G01X532227Y-39471D02*
X533101Y-38596D01*
X533756Y-37138D01*
X534193Y-35095D01*
X533756Y-33346D01*
X532883Y-32179D01*
X531354Y-31304D01*
X525459D01*
Y-48804D01*
X532664D01*
X534193Y-47638D01*
X535066Y-45887D01*
X535503Y-43846D01*
X535066Y-41804D01*
X533756Y-40054D01*
X532227Y-39471D01*
X525459D01*
G01X541431Y-54637D02*
X554531D01*
G01X560459Y-48804D02*
Y-31304D01*
X570503Y-48804D01*
Y-31304D01*
G01X582981Y-48804D02*
X581234Y-48512D01*
X579706Y-47346D01*
X578396Y-45596D01*
X577522Y-43554D01*
X577086Y-41221D01*
Y-38887D01*
X577522Y-36554D01*
X578396Y-34512D01*
X579706Y-32763D01*
X581234Y-31596D01*
X582981Y-31304D01*
X584727Y-31596D01*
X586256Y-32763D01*
X587566Y-34512D01*
X588440Y-36554D01*
X588876Y-38887D01*
Y-41221D01*
X588440Y-43554D01*
X587566Y-45596D01*
X586256Y-47346D01*
X584727Y-48512D01*
X582981Y-48804D01*
G01X633822Y-31304D02*
X639281Y-48804D01*
X644740Y-31304D01*
G01X661148Y-48804D02*
X652414D01*
Y-31304D01*
X661148D01*
G01X657654Y-39762D02*
X652414D01*
G01X669914Y-48804D02*
Y-31304D01*
X675373D01*
X677119Y-32179D01*
X678211Y-33346D01*
X678648Y-35679D01*
X678211Y-38013D01*
X676901Y-39471D01*
X675373Y-40346D01*
X669914D01*
G01X675373D02*
X678648Y-48804D01*
G01X691781Y-49387D02*
X691344Y-49096D01*
Y-48512D01*
X691781Y-48221D01*
X692218Y-48512D01*
Y-49096D01*
X691781Y-49387D01*
G01X661383Y-79221D02*
X662693Y-77471D01*
X664221Y-76596D01*
X665968Y-76304D01*
X668151Y-76887D01*
X669679Y-78346D01*
X670116Y-80095D01*
X669898Y-81846D01*
X669024Y-83304D01*
X664658Y-86221D01*
X662693Y-88262D01*
X661383Y-91180D01*
X660946Y-93804D01*
X670116D01*
G01X767364Y-31304D02*
Y-48804D01*
X776098D01*
G01X793161D02*
Y-37138D01*
G01Y-39179D02*
X792288Y-38013D01*
X790977Y-37429D01*
X789449Y-37138D01*
X787921Y-37721D01*
X786611Y-38887D01*
X785737Y-40637D01*
X785301Y-42971D01*
X785737Y-45304D01*
X786611Y-47054D01*
X787921Y-48221D01*
X789449Y-48804D01*
X790977Y-48512D01*
X792288Y-47638D01*
X793161Y-46471D01*
G01X802146Y-54054D02*
X803456Y-54637D01*
X805203Y-54054D01*
X806294Y-52888D01*
X807168Y-51429D01*
X808477Y-46763D01*
X811316Y-37138D01*
G01X804329D02*
X808477Y-46763D01*
G01X820956Y-40929D02*
X827943D01*
X827288Y-38887D01*
X826196Y-37721D01*
X824668Y-37138D01*
X823139Y-37429D01*
X821829Y-38304D01*
X820956Y-40346D01*
X820519Y-42096D01*
Y-43846D01*
X820956Y-45596D01*
X822048Y-47346D01*
X823358Y-48512D01*
X824886Y-48804D01*
X826414Y-48221D01*
X827943Y-46471D01*
G01X838674Y-48804D02*
Y-37138D01*
G01Y-39471D02*
X839766Y-38304D01*
X840858Y-37429D01*
X842386Y-37138D01*
X843477Y-37429D01*
X844788Y-38304D01*
G01X819848Y-76304D02*
Y-93804D01*
X811114D01*
G01X797981D02*
X796453Y-93512D01*
X794706Y-92638D01*
X793614Y-91180D01*
X793178Y-89137D01*
X793614Y-87096D01*
X794924Y-85346D01*
X796889Y-84471D01*
X799073D01*
X800383Y-83887D01*
X801475Y-82429D01*
X801911Y-80388D01*
X801256Y-78346D01*
X799728Y-76887D01*
X797981Y-76304D01*
X796235Y-76887D01*
X794706Y-78346D01*
X794051Y-80388D01*
X794488Y-82429D01*
X795579Y-83887D01*
X796889Y-84471D01*
X799073D01*
X801038Y-85346D01*
X802348Y-87096D01*
X802784Y-89137D01*
X802348Y-91180D01*
X801256Y-92638D01*
X799509Y-93512D01*
X797981Y-93804D01*
G01X931781D02*
X930034Y-93512D01*
X928506Y-92346D01*
X927196Y-90596D01*
X926322Y-88554D01*
X925886Y-86221D01*
Y-83887D01*
X926322Y-81554D01*
X927196Y-79512D01*
X928506Y-77763D01*
X930034Y-76596D01*
X931781Y-76304D01*
X933527Y-76596D01*
X935056Y-77763D01*
X936366Y-79512D01*
X937240Y-81554D01*
X937676Y-83887D01*
Y-86221D01*
X937240Y-88554D01*
X936366Y-90596D01*
X935056Y-92346D01*
X933527Y-93512D01*
X931781Y-93804D01*
G01X933527Y-89137D02*
X936148Y-93804D01*
G01X944478Y-76304D02*
Y-88846D01*
X945351Y-91471D01*
X947098Y-93221D01*
X949281Y-93804D01*
X951464Y-93221D01*
X953211Y-91471D01*
X954084Y-88846D01*
Y-76304D01*
G01X964161D02*
X969401D01*
G01X966781D02*
Y-93804D01*
G01X964161D02*
X969401D01*
G01X979259D02*
Y-76304D01*
X989303Y-93804D01*
Y-76304D01*
G01X1006584Y-77763D02*
X1005274Y-76887D01*
X1003746Y-76304D01*
X1001999D01*
X1000034Y-77179D01*
X998506Y-78637D01*
X997414Y-80388D01*
X996541Y-83304D01*
X996322Y-85929D01*
X996759Y-88554D01*
X997414Y-90304D01*
X998724Y-92054D01*
X1000253Y-93221D01*
X1001781Y-93804D01*
X1003309D01*
X1004838Y-93221D01*
X1006148Y-92346D01*
X1007240Y-91180D01*
G01X1019281Y-93804D02*
Y-85929D01*
X1014914Y-76304D01*
G01X1023648D02*
X1019281Y-85929D01*
G01X909478Y-48804D02*
Y-31304D01*
X913844D01*
X915591Y-32179D01*
X916901Y-33346D01*
X917993Y-35095D01*
X918866Y-37138D01*
X919084Y-40054D01*
X918866Y-42971D01*
X917993Y-45013D01*
X916901Y-46763D01*
X915591Y-47929D01*
X913844Y-48804D01*
X909478D01*
G01X928506Y-40929D02*
X935493D01*
X934838Y-38887D01*
X933746Y-37721D01*
X932218Y-37138D01*
X930689Y-37429D01*
X929379Y-38304D01*
X928506Y-40346D01*
X928069Y-42096D01*
Y-43846D01*
X928506Y-45596D01*
X929598Y-47346D01*
X930908Y-48512D01*
X932436Y-48804D01*
X933964Y-48221D01*
X935493Y-46471D01*
G01X946006Y-46763D02*
X947098Y-47929D01*
X948626Y-48804D01*
X949936D01*
X951246Y-48221D01*
X952119Y-47346D01*
X952556Y-46180D01*
X952338Y-44429D01*
X951464Y-43554D01*
X947534Y-41804D01*
X946661Y-39762D01*
X947098Y-38304D01*
X947971Y-37429D01*
X949281Y-37138D01*
X950591Y-37429D01*
X951901Y-38304D01*
G01X966781Y-37138D02*
Y-48804D01*
G01Y-32471D02*
X966344Y-32179D01*
Y-31596D01*
X966781Y-31304D01*
X967218Y-31596D01*
Y-32179D01*
X966781Y-32471D01*
G01X981224Y-53179D02*
X982753Y-54346D01*
X984499Y-54637D01*
X986027Y-54346D01*
X987338Y-52888D01*
X988211Y-50846D01*
Y-37138D01*
G01Y-39471D02*
X987338Y-38304D01*
X986027Y-37429D01*
X984499Y-37138D01*
X982753Y-37721D01*
X981661Y-38887D01*
X980787Y-40929D01*
X980351Y-42971D01*
X980569Y-44721D01*
X981443Y-46763D01*
X982753Y-48221D01*
X984499Y-48804D01*
X985809Y-48512D01*
X987338Y-47346D01*
X988211Y-46180D01*
G01X998069Y-48804D02*
Y-37138D01*
G01Y-40054D02*
X998943Y-38596D01*
X1000253Y-37429D01*
X1001999Y-37138D01*
X1003527Y-37429D01*
X1004838Y-38596D01*
X1005493Y-40637D01*
Y-48804D01*
G01X1016006Y-40929D02*
X1022993D01*
X1022338Y-38887D01*
X1021246Y-37721D01*
X1019718Y-37138D01*
X1018189Y-37429D01*
X1016879Y-38304D01*
X1016006Y-40346D01*
X1015569Y-42096D01*
Y-43846D01*
X1016006Y-45596D01*
X1017098Y-47346D01*
X1018408Y-48512D01*
X1019936Y-48804D01*
X1021464Y-48221D01*
X1022993Y-46471D01*
G01X1033724Y-48804D02*
Y-37138D01*
G01Y-39471D02*
X1034816Y-38304D01*
X1035908Y-37429D01*
X1037436Y-37138D01*
X1038527Y-37429D01*
X1039838Y-38304D01*
G01X1080481Y-76304D02*
X1078734Y-76887D01*
X1077424Y-78346D01*
X1076551Y-80095D01*
X1075896Y-82429D01*
X1075678Y-85054D01*
X1075896Y-87679D01*
X1076551Y-90013D01*
X1077424Y-91763D01*
X1078734Y-93221D01*
X1080481Y-93804D01*
X1082227Y-93221D01*
X1083538Y-91763D01*
X1084411Y-90013D01*
X1085066Y-87679D01*
X1085284Y-85054D01*
X1085066Y-82429D01*
X1084411Y-80095D01*
X1083538Y-78346D01*
X1082227Y-76887D01*
X1080481Y-76304D01*
G01X1097981Y-93804D02*
X1099509Y-93512D01*
X1101256Y-92638D01*
X1102348Y-91180D01*
X1102784Y-89137D01*
X1102348Y-87096D01*
X1101038Y-85346D01*
X1099073Y-84471D01*
X1096889D01*
X1095579Y-83887D01*
X1094487Y-82429D01*
X1094051Y-80388D01*
X1094706Y-78346D01*
X1096234Y-76887D01*
X1097981Y-76304D01*
X1099727Y-76887D01*
X1101256Y-78346D01*
X1101911Y-80388D01*
X1101474Y-82429D01*
X1100383Y-83887D01*
X1099073Y-84471D01*
X1096889D01*
X1094924Y-85346D01*
X1093614Y-87096D01*
X1093178Y-89137D01*
X1093614Y-91180D01*
X1094706Y-92638D01*
X1096453Y-93512D01*
X1097981Y-93804D01*
G01X1111551Y-94387D02*
X1119411Y-76304D01*
G01X1132981D02*
X1131234Y-76887D01*
X1129924Y-78346D01*
X1129051Y-80095D01*
X1128396Y-82429D01*
X1128178Y-85054D01*
X1128396Y-87679D01*
X1129051Y-90013D01*
X1129924Y-91763D01*
X1131234Y-93221D01*
X1132981Y-93804D01*
X1134727Y-93221D01*
X1136038Y-91763D01*
X1136911Y-90013D01*
X1137566Y-87679D01*
X1137784Y-85054D01*
X1137566Y-82429D01*
X1136911Y-80095D01*
X1136038Y-78346D01*
X1134727Y-76887D01*
X1132981Y-76304D01*
G01X1150044Y-93804D02*
X1150481Y-90013D01*
X1151136Y-86804D01*
X1152009Y-83887D01*
X1153101Y-80679D01*
X1154848Y-76304D01*
X1146114D01*
G01X1164051Y-94387D02*
X1171911Y-76304D01*
G01X1181333Y-79221D02*
X1182643Y-77471D01*
X1184171Y-76596D01*
X1185918Y-76304D01*
X1188101Y-76887D01*
X1189629Y-78346D01*
X1190066Y-80095D01*
X1189848Y-81846D01*
X1188974Y-83304D01*
X1184608Y-86221D01*
X1182643Y-88262D01*
X1181333Y-91180D01*
X1180896Y-93804D01*
X1190066D01*
G01X1202981Y-76304D02*
X1201234Y-76887D01*
X1199924Y-78346D01*
X1199051Y-80095D01*
X1198396Y-82429D01*
X1198178Y-85054D01*
X1198396Y-87679D01*
X1199051Y-90013D01*
X1199924Y-91763D01*
X1201234Y-93221D01*
X1202981Y-93804D01*
X1204727Y-93221D01*
X1206038Y-91763D01*
X1206911Y-90013D01*
X1207566Y-87679D01*
X1207784Y-85054D01*
X1207566Y-82429D01*
X1206911Y-80095D01*
X1206038Y-78346D01*
X1204727Y-76887D01*
X1202981Y-76304D01*
G01X1220481Y-93804D02*
Y-76304D01*
X1217861Y-79804D01*
G01Y-93804D02*
X1223101D01*
G01X1237544D02*
X1237981Y-90013D01*
X1238636Y-86804D01*
X1239509Y-83887D01*
X1240601Y-80679D01*
X1242348Y-76304D01*
X1233614D01*
G01X1128178Y-48804D02*
Y-31304D01*
X1132544D01*
X1134291Y-32179D01*
X1135601Y-33346D01*
X1136693Y-35095D01*
X1137566Y-37138D01*
X1137784Y-40054D01*
X1137566Y-42971D01*
X1136693Y-45013D01*
X1135601Y-46763D01*
X1134291Y-47929D01*
X1132544Y-48804D01*
X1128178D01*
G01X1154411D02*
Y-37138D01*
G01Y-39179D02*
X1153538Y-38013D01*
X1152227Y-37429D01*
X1150699Y-37138D01*
X1149171Y-37721D01*
X1147861Y-38887D01*
X1146987Y-40637D01*
X1146551Y-42971D01*
X1146987Y-45304D01*
X1147861Y-47054D01*
X1149171Y-48221D01*
X1150699Y-48804D01*
X1152227Y-48512D01*
X1153538Y-47638D01*
X1154411Y-46471D01*
G01X1167981Y-31304D02*
Y-48804D01*
G01X1164924Y-37138D02*
X1171038D01*
G01X1182206Y-40929D02*
X1189193D01*
X1188538Y-38887D01*
X1187446Y-37721D01*
X1185918Y-37138D01*
X1184389Y-37429D01*
X1183079Y-38304D01*
X1182206Y-40346D01*
X1181769Y-42096D01*
Y-43846D01*
X1182206Y-45596D01*
X1183298Y-47346D01*
X1184608Y-48512D01*
X1186136Y-48804D01*
X1187664Y-48221D01*
X1189193Y-46471D01*
G54D36*
X99874Y535824D03*
X86200Y677300D03*
X175548Y568251D03*
X186489Y582625D03*
X286211Y553256D03*
X860686Y159490D03*
X872998Y391533D03*
G54D45*
X141887Y560491D03*
X146567Y560391D03*
X151257Y560423D03*
X203000Y517200D03*
X198000D03*
X208000D03*
X144037Y549486D03*
X197230Y571870D03*
X181505Y575791D03*
X160964Y717468D03*
X218000Y517200D03*
X493500Y53700D03*
X446403Y31900D03*
X506500Y53700D03*
X860504Y168244D03*
X861511Y357363D03*
G54D18*
X64151Y517477D03*
X64251Y509877D03*
X120273Y500759D03*
X86659Y517477D03*
X86673Y510000D03*
X81032Y517477D03*
X81068Y509866D03*
X92286Y517477D03*
X92273Y510000D03*
X97913Y517477D03*
X97900Y510000D03*
X69778Y517477D03*
X69878Y509777D03*
X75405Y517477D03*
X75373Y509879D03*
X121643Y618027D03*
X148000Y475500D03*
X143700D03*
X152589Y489481D03*
X192300Y493500D03*
X212118Y470993D03*
X167000Y520500D03*
X146700Y530100D03*
X156501Y564267D03*
X162700Y495700D03*
X158600Y528400D03*
X167454Y530877D03*
X163300Y530600D03*
X174900Y506500D03*
X200910Y563190D03*
X179400Y531800D03*
X183670Y531766D03*
X196013Y536175D03*
X146600Y520700D03*
X196890Y567300D03*
X184400Y611300D03*
X212500Y611900D03*
X155341Y616572D03*
X196500Y611300D03*
X194718Y625994D03*
X184700Y591000D03*
X218500Y490700D03*
X273809Y563811D03*
X215448Y535601D03*
X269709Y563813D03*
X224000Y622700D03*
X238100Y586400D03*
X252300Y580700D03*
X242100Y586400D03*
X296680Y556264D03*
X288286Y579720D03*
X309765Y603700D03*
X344102Y594663D03*
X312000Y666700D03*
X307849Y668900D03*
X358120Y547604D03*
X357500Y566900D03*
X369800Y578000D03*
X380000Y601800D03*
X357655Y681145D03*
X521330Y85580D03*
X815016Y348514D03*
X819100Y393600D03*
G54D54*
X354800Y612600D03*
X351200D03*
G54D63*
X801024Y24409D03*
X811024D03*
X821024D03*
G54D27*
X64350Y576900D03*
X129100Y596500D03*
X141189Y595737D03*
X148840Y549535D03*
X153495Y549566D03*
X213000Y517200D03*
X245100Y630200D03*
X354000Y632100D03*
X349200D03*
X377714Y621980D03*
X375600Y598600D03*
G54D73*
G01X194094Y602362D02*
X198724D01*
X199162Y602800D01*
G01D02*
X199600D01*
X200550Y603750D01*
Y608800D01*
G54D64*
X850667Y383181D03*
G54D55*
X380500Y24500D03*
X369500D03*
X478429Y25800D03*
X467429D03*
G54D46*
X141887Y566091D03*
X146567Y565991D03*
X151257Y566023D03*
X203000Y522800D03*
X198000D03*
X208000D03*
X144037Y555086D03*
X197230Y577470D03*
X181505Y581391D03*
X160964Y723068D03*
X218000Y522800D03*
X493500Y59300D03*
X446403Y37500D03*
X506500Y59300D03*
X860504Y173844D03*
X861511Y362963D03*
G54D37*
X100130Y576452D03*
X85700Y681400D03*
X171969Y579940D03*
X211700Y638400D03*
X216200Y467300D03*
X222019Y634188D03*
X297800Y527900D03*
X328123Y579949D03*
X698225Y445986D03*
X687000Y496509D03*
Y500209D03*
X883986Y269745D03*
X861498Y348715D03*
G54D19*
X64151Y514077D03*
X64251Y506477D03*
X120273Y497359D03*
X86659Y514077D03*
X86673Y506600D03*
X81032Y514077D03*
X81068Y506466D03*
X92286Y514077D03*
X92273Y506600D03*
X97913Y514077D03*
X97900Y506600D03*
X69778Y514077D03*
X69878Y506377D03*
X75405Y514077D03*
X75373Y506479D03*
X121643Y614627D03*
X162700Y492300D03*
X148000Y472100D03*
X143700D03*
X152589Y486081D03*
X192300Y490100D03*
X212118Y467593D03*
X167000Y517100D03*
X146700Y526700D03*
X156501Y560867D03*
X196890Y563900D03*
X158600Y525000D03*
X167454Y527477D03*
X163300Y527200D03*
X174900Y503100D03*
X200910Y559790D03*
X179400Y528400D03*
X183670Y528366D03*
X196013Y532775D03*
X146600Y517300D03*
X184400Y607900D03*
X212500Y608500D03*
X155341Y613172D03*
X196500Y607900D03*
X194718Y622594D03*
X184700Y587600D03*
X218500Y487300D03*
X273809Y560411D03*
X215448Y532201D03*
X269709Y560413D03*
X224000Y619300D03*
X238100Y583000D03*
X252300Y577300D03*
X242100Y583000D03*
X296680Y552864D03*
X288286Y576320D03*
X309765Y600300D03*
X344102Y591263D03*
X312000Y663300D03*
X307849Y665500D03*
X357500Y563500D03*
X358120Y544204D03*
X369800Y574600D03*
X380000Y598400D03*
X357655Y677745D03*
X521330Y82180D03*
X815016Y345114D03*
X819100Y390200D03*
G54D28*
X60600Y670900D03*
X65900Y671000D03*
X65714Y665850D03*
X60800Y660900D03*
X60700Y665900D03*
X65700Y660900D03*
X139916Y709422D03*
X130019Y709695D03*
X139916Y705822D03*
X130019Y706095D03*
X135019D03*
X70700Y671000D03*
X70800Y660700D03*
X70600Y665800D03*
X139916Y713022D03*
Y716622D03*
Y720222D03*
Y723822D03*
X130019Y713295D03*
Y716895D03*
Y720495D03*
X135019Y710595D03*
Y723595D03*
Y719095D03*
Y714845D03*
X130019Y724095D03*
X265400Y446100D03*
X260513Y564135D03*
X312289Y535181D03*
X311386Y633450D03*
X306300Y638600D03*
X301286Y638650D03*
X301386Y633650D03*
X306286D03*
X311186Y638550D03*
X300720Y704920D03*
X300520Y710020D03*
X290620Y710120D03*
X295634Y710070D03*
X290720Y705120D03*
X295620D03*
X301186Y643650D03*
X306486Y643750D03*
X311286D03*
X300620Y715220D03*
X290520Y715120D03*
X295820Y715220D03*
X365164Y612620D03*
X358864D03*
X371400Y606400D03*
X358800Y606300D03*
X365300Y606500D03*
X371400Y612700D03*
X371300Y618800D03*
X365500Y619000D03*
X358900Y618800D03*
X468000Y31500D03*
Y39500D03*
X464000Y35500D03*
X468000Y35400D03*
X472000Y35500D03*
X603943Y42806D03*
X608143Y42906D03*
X603943Y47006D03*
X608043D03*
X706275Y445986D03*
X753800Y535000D03*
X857020Y383172D03*
Y379572D03*
Y386772D03*
X875272Y186265D03*
X878872D03*
X860872D03*
X871672D03*
X868072D03*
X864472D03*
X878372Y191265D03*
X878872Y196265D03*
X864472D03*
X868072D03*
X871672D03*
X875272D03*
X865372Y191265D03*
X873872D03*
X869622D03*
X860872Y196265D03*
Y191265D03*
X871420Y383172D03*
X875020D03*
Y379572D03*
X871420D03*
X867820D03*
X860620D03*
X864220D03*
X875020Y386772D03*
X871420D03*
X867820D03*
X860620D03*
X864220D03*
X867820Y383172D03*
X860620D03*
X864220D03*
G54D74*
G01X63050Y569822D02*
X63731Y569141D01*
X65354D01*
X66278Y568217D01*
Y557122D01*
X66858Y556542D01*
X69427D01*
X71002Y558117D01*
G54D29*
X127400Y504600D03*
X152316Y570305D03*
X175579Y583387D03*
X207500Y634400D03*
X254800Y609800D03*
X288336Y598419D03*
X359489Y540188D03*
X369409Y509699D03*
X365780Y551390D03*
X671232Y486702D03*
Y490702D03*
Y494202D03*
Y482602D03*
G54D65*
X853167Y383181D03*
G54D38*
X103730Y576452D03*
X89300Y681400D03*
X175569Y579940D03*
X219800Y467300D03*
X225619Y634188D03*
X215300Y638400D03*
X301400Y527900D03*
X331723Y579949D03*
X701825Y445986D03*
X690600Y496509D03*
Y500209D03*
X887586Y269745D03*
X865098Y348715D03*
G54D47*
G01X187500Y523700D02*
X187400Y523800D01*
Y527000D01*
X189400Y529000D01*
X193150D01*
X193650Y528500D01*
G01X175852Y574058D02*
Y576712D01*
X175298Y577266D01*
X168898Y548819D03*
X184645Y539370D03*
X194094D03*
X203542Y545671D03*
X197243Y539371D03*
X194093Y564569D03*
X190944D03*
X194093Y555120D03*
X184646D03*
X153149Y536221D03*
X165748Y558268D03*
X172048Y555120D03*
X156297Y558267D03*
X187925Y564617D03*
X168898Y561417D03*
X206692Y555120D03*
X165745Y564567D03*
X168895D03*
X159449Y561417D03*
X165748D03*
X172047D03*
X162598Y558268D03*
X168898D03*
X165748Y555118D03*
X159449D03*
X162599Y551970D03*
X194093D03*
X197243D03*
X181497D03*
X175197D03*
X178347D03*
X203542Y555120D03*
X187795D03*
X200393Y551970D03*
X206692Y558269D03*
Y561419D03*
Y564569D03*
X175196Y558269D03*
X190945Y545669D03*
X172047D03*
Y551970D03*
X159449Y545671D03*
X162599Y545669D03*
X165749D03*
X212991Y561419D03*
X184646Y548821D03*
Y545671D03*
X184645Y542519D03*
X206693Y542520D03*
X159449Y542521D03*
X171906Y534661D03*
X212991Y542519D03*
X156299Y545671D03*
X165749Y548819D03*
X175197Y545671D03*
X162599Y542519D03*
X168898D03*
X156299Y542521D03*
X181496Y542520D03*
X159449Y548821D03*
X194094Y542519D03*
X172047Y548819D03*
X168898Y551969D03*
X162599Y548821D03*
X162598Y561417D03*
X168898Y555119D03*
X181497Y548821D03*
X178346Y545670D03*
X181497Y545671D03*
X162595Y564567D03*
X203542Y551970D03*
X181497Y555120D03*
X178346Y555119D03*
X187885Y552058D03*
X197245Y555118D03*
X159412Y552006D03*
X165748Y551968D03*
X178347Y564569D03*
X203543Y561418D03*
Y564568D03*
X172047D03*
X200393Y548819D03*
X209842Y545669D03*
Y564567D03*
Y558268D03*
X212992Y551969D03*
Y548819D03*
X209842Y561417D03*
X212992Y564567D03*
X200393Y545669D03*
X206692Y545671D03*
X209842Y548819D03*
X212992Y545669D03*
X165777Y542555D03*
X209842Y555119D03*
Y551969D03*
X206692Y548820D03*
X206693Y551969D03*
X194094Y545669D03*
Y548820D03*
X175197Y548821D03*
X168898Y545669D03*
X153150Y539371D03*
X153149Y542521D03*
X197244Y545669D03*
Y542519D03*
X156300Y539371D03*
X197243Y589900D03*
X194094Y602362D03*
X206692Y596063D03*
X203450Y592912D03*
X194093Y596063D03*
X172020Y577050D03*
X175196Y589764D03*
X190944Y577166D03*
X194093Y574016D03*
Y567718D03*
X190944Y574016D03*
Y567718D03*
X187795Y577166D03*
X184646D03*
X172048Y589764D03*
X168898D03*
X187844Y574065D03*
X184645Y574166D03*
X187746Y567669D03*
X184695Y567666D03*
X184646Y570867D03*
X168898Y570866D03*
X156299Y586614D03*
Y580315D03*
X159449Y567717D03*
X156299Y570866D03*
X200393Y589764D03*
X187900Y589800D03*
X187794Y586614D03*
X203542Y589764D03*
X200393Y596063D03*
X187795Y592914D03*
X203605Y605821D03*
X187795Y602363D03*
X153149Y605513D03*
X206692Y592913D03*
X165748Y583464D03*
X209842D03*
X212992Y586614D03*
X212991Y567718D03*
X209841Y574016D03*
X206692D03*
X168898Y567717D03*
X159449Y570866D03*
X168898Y583464D03*
Y577165D03*
X159449Y586614D03*
X162598Y580315D03*
Y586614D03*
X165748D03*
X168898D03*
X159449Y577165D03*
X156299D03*
X168898Y580315D03*
X159449D03*
X162598Y577165D03*
X165748Y580315D03*
X162598Y583464D03*
X165748Y570866D03*
Y567717D03*
X162598D03*
X172047Y570867D03*
X194094Y577166D03*
X203543Y574017D03*
X178347Y589764D03*
X181497D03*
X194093Y586614D03*
X209841Y596063D03*
X206692Y583465D03*
Y567600D03*
X212992Y580315D03*
X212991Y577165D03*
X209842Y567717D03*
X212991Y574016D03*
X190945Y599213D03*
X190944Y596063D03*
X187796Y599212D03*
X181586Y599123D03*
X212991Y583465D03*
X209841Y577165D03*
X159448Y596063D03*
X190944Y602362D03*
X203543D03*
X203542Y596063D03*
X194094Y599213D03*
X168898Y596063D03*
X212992Y602363D03*
X212991Y599212D03*
X206692Y589763D03*
X168898Y592913D03*
X162598Y596063D03*
X194093Y589764D03*
Y592913D03*
X206692Y586614D03*
X209842Y586613D03*
X212992Y589764D03*
X209841Y592913D03*
X162598Y570866D03*
X178347Y574018D03*
X203542Y580315D03*
Y586614D03*
X190944D03*
X178346Y586615D03*
X181497Y586614D03*
X178344Y577166D03*
X203542Y577165D03*
X178347Y570769D03*
X203501Y571005D03*
X175298Y577266D03*
X172047Y567717D03*
X178346Y596064D03*
X178347Y599213D03*
X165748D03*
X168898D03*
X162598D03*
X159448D03*
X172048Y596063D03*
X190944Y592913D03*
Y589764D03*
X200393Y586614D03*
X197165Y586540D03*
X212993Y592912D03*
X209842Y589763D03*
X206692Y580315D03*
X209841D03*
X181500Y595900D03*
X200393Y592912D03*
X209841Y599212D03*
X200393D03*
X159448Y589764D03*
Y592913D03*
X162598Y589764D03*
X165748D03*
Y596063D03*
Y592913D03*
X175197D03*
X172048D03*
X181530Y592765D03*
X175197Y596063D03*
Y599213D03*
X172048D03*
X216141Y564569D03*
Y561419D03*
X219291Y542519D03*
X216141D03*
X216142Y548820D03*
X216141Y555120D03*
Y558269D03*
X222441Y548820D03*
X219291D03*
X216141Y551970D03*
X216142Y545669D03*
X216141Y580315D03*
X222440Y605512D03*
X216141Y577165D03*
Y583465D03*
Y586614D03*
Y567718D03*
X219293Y567717D03*
X216141Y574016D03*
Y599212D03*
Y589762D03*
X230600Y608100D03*
X355600Y172900D03*
X363400Y115950D03*
X815600Y386200D03*
G54D56*
G01X53302Y567317D02*
X53301Y567316D01*
X47668D01*
X421653Y126378D03*
X428740Y121654D03*
X421653Y130709D03*
X428740Y125985D03*
X421653Y136221D03*
X428740Y131496D03*
Y135827D03*
X421653Y183071D03*
Y140551D03*
Y144882D03*
X428740Y140158D03*
X421653Y150394D03*
X428740Y145670D03*
X421653Y154725D03*
X428740Y150000D03*
X421653Y159055D03*
X428740Y154331D03*
X421653Y164567D03*
X428740Y159843D03*
X421653Y168898D03*
X428740Y164173D03*
X421653Y173229D03*
X428740Y168504D03*
X421653Y178740D03*
X428740Y174016D03*
X435827Y126378D03*
X450000D03*
X464173D03*
X442913Y121654D03*
X457086D03*
X471260D03*
X435827Y130709D03*
X442913Y125985D03*
X450000Y130709D03*
X457086Y125985D03*
X464173Y130709D03*
X471260Y125985D03*
X435827Y136221D03*
X442913Y131496D03*
X450000Y136221D03*
X457086Y131496D03*
X464173Y136221D03*
X471260Y131496D03*
X442913Y135827D03*
X457086D03*
X471260D03*
X435827Y183071D03*
X450000D03*
X464173D03*
X435827Y140551D03*
X450000D03*
X464173D03*
X435827Y144882D03*
X442913Y140158D03*
X450000Y144882D03*
X457086Y140158D03*
X464173Y144882D03*
X471260Y140158D03*
X435827Y150394D03*
X442913Y145670D03*
X450000Y150394D03*
X457086Y145670D03*
X464173Y150394D03*
X471260Y145670D03*
X435827Y154725D03*
X442913Y150000D03*
X450000Y154725D03*
X457086Y150000D03*
X464173Y154725D03*
X471260Y150000D03*
X435827Y159055D03*
X442913Y154331D03*
X450000Y159055D03*
X457086Y154331D03*
X464173Y159055D03*
X471260Y154331D03*
X435827Y164567D03*
X442913Y159843D03*
X450000Y164567D03*
X457086Y159843D03*
X464173Y164567D03*
X471260Y159843D03*
X435827Y168898D03*
X442913Y164173D03*
X450000Y168898D03*
X457086Y164173D03*
X464173Y168898D03*
X471260Y164173D03*
X435827Y173229D03*
X442913Y168504D03*
X450000Y173229D03*
X457086Y168504D03*
X464173Y173229D03*
X471260Y168504D03*
X435827Y178740D03*
X442913Y174016D03*
X450000Y178740D03*
X457086Y174016D03*
X464173Y178740D03*
X471260Y174016D03*
X506693Y126378D03*
X520866D03*
X535039D03*
X549212D03*
X513779Y121654D03*
X527953D03*
X542126D03*
X556299D03*
X506693Y130709D03*
X513779Y125985D03*
X520866Y130709D03*
X527953Y125985D03*
X535039Y130709D03*
X542126Y125985D03*
X549212Y130709D03*
X556299Y125985D03*
X506693Y136221D03*
X513779Y131496D03*
X520866Y136221D03*
X527953Y131496D03*
X535039Y136221D03*
X542126Y131496D03*
X549212Y136221D03*
X556299Y131496D03*
X513779Y135827D03*
X527953D03*
X542126D03*
X556299D03*
X506693Y183071D03*
X520866D03*
X535039D03*
X549212D03*
X506693Y140551D03*
X520866D03*
X535039D03*
X549212D03*
X506693Y144882D03*
X513779Y140158D03*
X520866Y144882D03*
X527953Y140158D03*
X535039Y144882D03*
X542126Y140158D03*
X549212Y144882D03*
X556299Y140158D03*
X506693Y150394D03*
X513779Y145670D03*
X520866Y150394D03*
X527953Y145670D03*
X535039Y150394D03*
X542126Y145670D03*
X549212Y150394D03*
X556299Y145670D03*
X506693Y154725D03*
X513779Y150000D03*
X520866Y154725D03*
X527953Y150000D03*
X535039Y154725D03*
X542126Y150000D03*
X549212Y154725D03*
X556299Y150000D03*
X506693Y159055D03*
X513779Y154331D03*
X520866Y159055D03*
X527953Y154331D03*
X535039Y159055D03*
X542126Y154331D03*
X549212Y159055D03*
X556299Y154331D03*
X506693Y164567D03*
X513779Y159843D03*
X520866Y164567D03*
X527953Y159843D03*
X535039Y164567D03*
X542126Y159843D03*
X549212Y164567D03*
X556299Y159843D03*
X506693Y168898D03*
X513779Y164173D03*
X520866Y168898D03*
X527953Y164173D03*
X535039Y168898D03*
X542126Y164173D03*
X549212Y168898D03*
X556299Y164173D03*
X506693Y173229D03*
X513779Y168504D03*
X520866Y173229D03*
X527953Y168504D03*
X535039Y173229D03*
X542126Y168504D03*
X549212Y173229D03*
X556299Y168504D03*
X506693Y178740D03*
X513779Y174016D03*
X520866Y178740D03*
X527953Y174016D03*
X535039Y178740D03*
X542126Y174016D03*
X549212Y178740D03*
X556299Y174016D03*
G54D75*
G01X81975Y554363D02*
X83192Y555580D01*
X86135D01*
X86750Y554965D01*
G01X81974Y558398D02*
X83192Y557180D01*
X85815D01*
X86750Y558115D01*
G54D66*
G01X190944Y592913D02*
Y589764D01*
G01X316350Y515460D02*
X312400D01*
X311900Y514960D01*
Y514950D01*
G01X345239Y661689D02*
X340511D01*
X340000Y662200D01*
G01X811748Y422637D02*
Y418405D01*
X809702Y416359D01*
G54D48*
X163189Y669291D03*
G54D39*
X96287Y576499D03*
X143823Y615646D03*
X250300Y633600D03*
X354662Y523046D03*
X308700Y515500D03*
X360980Y590486D03*
X586447Y60807D03*
X815334Y393662D03*
X806825Y424215D03*
G54D57*
X428740Y179528D03*
X457086D03*
X442913D03*
X471260D03*
X513779D03*
X527953D03*
X542126D03*
X556299D03*
G54D76*
G01X471260Y174016D02*
Y172516D01*
G03X471903Y171873I643J0D01*
G01X473900D01*
G02X476500Y169273I0J-2600D01*
G01Y114100D01*
X463700Y101300D01*
X459700D01*
X446842Y88442D01*
X398815D01*
X379968Y100680D01*
X371097Y114336D01*
X358776Y122335D01*
X351330Y133798D01*
X347414Y152213D01*
X342130Y177058D01*
X345595Y193347D01*
X342560Y207618D01*
X346056Y224070D01*
X339644Y254356D01*
X334000Y260000D01*
X310200D01*
X308075Y257875D01*
X303092D01*
X300863Y260104D01*
Y265907D01*
X302327Y267371D01*
X303411D01*
X304548Y268508D01*
G01X471260Y168504D02*
Y170004D01*
G02X471904Y170648I644J0D01*
G01X473900D01*
G02X475275Y169273I0J-1375D01*
G01Y114608D01*
X463192Y102525D01*
X459192D01*
X446334Y89667D01*
X443090D01*
X442490Y90267D01*
X440765D01*
X440165Y89667D01*
X438440D01*
X437840Y90267D01*
X436115D01*
X435515Y89667D01*
X433790D01*
X433190Y90267D01*
X431465D01*
X430865Y89667D01*
X429140D01*
X428540Y90267D01*
X426815D01*
X426215Y89667D01*
X399178D01*
X397731Y90606D01*
X397555Y91436D01*
X396108Y92376D01*
X395278Y92200D01*
X393831Y93139D01*
X393655Y93969D01*
X392208Y94909D01*
X391378Y94732D01*
X389931Y95672D01*
X389755Y96501D01*
X388308Y97441D01*
X387478Y97265D01*
X386031Y98204D01*
X385855Y99034D01*
X384408Y99974D01*
X383578Y99797D01*
X380854Y101566D01*
X371983Y115222D01*
X359662Y123221D01*
X352481Y134275D01*
X352123Y135961D01*
X352122Y135962D01*
X352584Y136674D01*
X352225Y138361D01*
X351514Y138823D01*
X351155Y140510D01*
X351617Y141222D01*
X351258Y142909D01*
X350547Y143371D01*
X350188Y145058D01*
X350650Y145770D01*
X350291Y147457D01*
X349580Y147919D01*
X349221Y149606D01*
X349683Y150318D01*
X349324Y152005D01*
X348613Y152467D01*
X343383Y177058D01*
X346848Y193347D01*
X343813Y207618D01*
X347309Y224070D01*
X346941Y225809D01*
X347404Y226521D01*
X347046Y228208D01*
X346335Y228671D01*
X345978Y230359D01*
X346440Y231070D01*
X346083Y232757D01*
X345372Y233220D01*
X345015Y234908D01*
X345477Y235619D01*
X345120Y237306D01*
X344409Y237769D01*
X344052Y239457D01*
X344514Y240168D01*
X344157Y241855D01*
X343446Y242318D01*
X340768Y254966D01*
X334508Y261225D01*
X309692D01*
X307567Y259100D01*
X303600D01*
X302088Y260612D01*
Y265399D01*
X302835Y266146D01*
X303410D01*
X304548Y265008D01*
G01X471260Y131496D02*
Y129996D01*
G02X470617Y129353I-643J0D01*
G01X469184D01*
G03X467104Y127273I0J-2080D01*
G01Y116137D01*
X458592Y107625D01*
X456993D01*
X444793Y95425D01*
X402195D01*
X387886Y104938D01*
X358258Y150538D01*
X350669Y186250D01*
X352146Y193170D01*
X349217Y207804D01*
X353141Y226753D01*
X344674Y269059D01*
X336534Y277200D01*
X313933D01*
X311179Y279954D01*
X308705D01*
X307567Y281092D01*
G01X471260Y125985D02*
Y127485D01*
G03X470617Y128128I-643J0D01*
G01X469184D01*
G03X468329Y127273I0J-855D01*
G01Y115629D01*
X459100Y106400D01*
X457501D01*
X445301Y94200D01*
X401824D01*
X386996Y104057D01*
X357107Y150061D01*
X349416Y186251D01*
X350895Y193178D01*
X347966Y207808D01*
X351890Y226757D01*
X343545Y268455D01*
X336026Y275975D01*
X313425D01*
X310671Y278729D01*
X308704D01*
X307567Y277592D01*
G01X464173Y136221D02*
Y134721D01*
G02X463530Y134078I-643J0D01*
G01X462126D01*
G03X460017Y131969I0J-2109D01*
G01Y115549D01*
X457093Y112625D01*
X455493D01*
X442893Y100025D01*
X404070D01*
X392104Y108005D01*
X367583Y145065D01*
X354083Y209005D01*
X357949Y227680D01*
X346163Y284269D01*
X335733Y294700D01*
X332467D01*
X330800Y293033D01*
Y291133D01*
X328292Y288625D01*
X311308D01*
X307378Y292555D01*
X305404D01*
X304267Y293692D01*
G01X464173Y130709D02*
Y132209D01*
G03X463529Y132853I-644J0D01*
G01X462126D01*
G03X461242Y131969I0J-884D01*
G01Y115041D01*
X457601Y111400D01*
X456001D01*
X443401Y98800D01*
X403698D01*
X391218Y107122D01*
X366432Y144583D01*
X352831Y209003D01*
X356697Y227679D01*
X345038Y283661D01*
X335225Y293475D01*
X332975D01*
X332025Y292525D01*
Y290625D01*
X328800Y287400D01*
X310800D01*
X306870Y291330D01*
X305405D01*
X304267Y290192D01*
G01X457086Y131496D02*
Y129996D01*
G02X456443Y129353I-643J0D01*
G01X455010D01*
G03X452931Y127274I0J-2079D01*
G01Y118931D01*
X438625Y104625D01*
X406783D01*
X395317Y112282D01*
X371845Y147497D01*
X361911Y194243D01*
X362761Y198242D01*
X359569Y213259D01*
X362748Y228222D01*
X350596Y285950D01*
X341873Y299327D01*
X340175Y301025D01*
X333808D01*
X332275Y302558D01*
Y304758D01*
X329508Y307525D01*
X317492D01*
X315122Y305155D01*
X308704D01*
X307567Y306292D01*
G01X457086Y125985D02*
Y127485D01*
G03X456443Y128128I-643J0D01*
G01X455010D01*
G03X454156Y127274I0J-854D01*
G01Y118423D01*
X439133Y103400D01*
X406411D01*
X394433Y111399D01*
X370695Y147012D01*
X360658Y194243D01*
X361508Y198242D01*
X358316Y213259D01*
X361495Y228223D01*
X349444Y285473D01*
X340916Y298550D01*
X339667Y299800D01*
X333300D01*
X331050Y302050D01*
Y304250D01*
X329000Y306300D01*
X318000D01*
X315630Y303930D01*
X308705D01*
X307567Y302792D01*
G01X450000Y136221D02*
Y134721D01*
G02X449357Y134078I-643J0D01*
G01X447953D01*
G03X445844Y131969I0J-2109D01*
G01Y120201D01*
X434768Y109125D01*
X408957D01*
X398363Y116199D01*
X376172Y149607D01*
X368324Y186527D01*
X370569Y197744D01*
X366158Y218414D01*
X369562Y234424D01*
X357653Y291063D01*
X342435Y314499D01*
X342344Y314590D01*
X342343D01*
X337133Y319800D01*
X333467D01*
X327892Y314225D01*
X313708D01*
X310178Y317755D01*
X305404D01*
X304267Y318892D01*
G01X450000Y130709D02*
Y132209D01*
G03X449356Y132853I-644J0D01*
G01X447953D01*
G03X447069Y131969I0J-884D01*
G01Y119693D01*
X435276Y107900D01*
X408585D01*
X397478Y115316D01*
X375022Y149124D01*
X367073Y186520D01*
X369318Y197736D01*
X364905Y218413D01*
X368309Y234425D01*
X356501Y290587D01*
X341477Y313723D01*
X336625Y318575D01*
X333975D01*
X328400Y313000D01*
X313200D01*
X309670Y316530D01*
X305405D01*
X304267Y315392D01*
G01X442913Y131496D02*
Y129996D01*
G02X442270Y129353I-643J0D01*
G01X440837D01*
G03X438758Y127274I0J-2079D01*
G01Y120910D01*
X431473Y113625D01*
X417463D01*
X408600Y115466D01*
X401045Y120503D01*
X380376Y151546D01*
X373260Y185010D01*
X376803Y202506D01*
X372656Y222013D01*
X374857Y232370D01*
X361991Y294208D01*
X344802Y320731D01*
X338508Y327025D01*
X334709D01*
X329007Y332725D01*
X316392D01*
X314021Y330354D01*
X308705D01*
X307567Y331492D01*
G01X442913Y125985D02*
Y127485D01*
G03X442270Y128128I-643J0D01*
G01X440837D01*
G03X439983Y127274I0J-854D01*
G01Y120402D01*
X431981Y112400D01*
X417337D01*
X408118Y114314D01*
X400161Y119620D01*
X379226Y151062D01*
X372008Y185004D01*
X375551Y202500D01*
X371403Y222013D01*
X373605Y232373D01*
X360838Y293734D01*
X343844Y319956D01*
X338000Y325800D01*
X334201D01*
X328499Y331500D01*
X316900D01*
X314529Y329129D01*
X308704D01*
X307567Y327992D01*
G01X435827Y136221D02*
Y134721D01*
G02X435184Y134078I-643J0D01*
G01X433780D01*
G03X431671Y131969I0J-2109D01*
G01Y120246D01*
X429627Y118202D01*
X418845D01*
X412848Y119401D01*
X402806Y126099D01*
X384623Y153458D01*
X377908Y185055D01*
X381441Y202395D01*
X377640Y220277D01*
X379911Y230960D01*
X366265Y296393D01*
X345220Y328786D01*
X343440Y337154D01*
X340283Y342018D01*
X336300Y346000D01*
X333200D01*
X331300Y344100D01*
Y342400D01*
X328525Y339625D01*
X314007D01*
X310708Y342925D01*
X305434D01*
X304267Y344092D01*
G01X435827Y130709D02*
Y132209D01*
G03X435183Y132853I-644J0D01*
G01X433780D01*
G03X432896Y131969I0J-884D01*
G01Y119738D01*
X430135Y116977D01*
X418723D01*
X412370Y118247D01*
X401921Y125216D01*
X383473Y152975D01*
X376656Y185050D01*
X380189Y202390D01*
X376387Y220277D01*
X378659Y230962D01*
X378658D01*
X365112Y295918D01*
X344069Y328309D01*
X342289Y336677D01*
X339325Y341242D01*
X335792Y344775D01*
X333708D01*
X332525Y343592D01*
Y341892D01*
X329033Y338400D01*
X313499D01*
X310200Y341700D01*
X305375D01*
X304267Y340592D01*
G01X428740Y131496D02*
Y129996D01*
G02X428097Y129353I-643J0D01*
G01X426664D01*
G03X424584Y127273I0J-2080D01*
G01Y124554D01*
X422776Y122746D01*
X421206D01*
X417682Y123451D01*
X404741Y132046D01*
X388878Y155843D01*
X382604Y185356D01*
X386049Y202437D01*
X382571Y218801D01*
X384917Y229845D01*
X370636Y298239D01*
X349582Y330662D01*
X346931Y343139D01*
X344403Y347031D01*
X340933Y350500D01*
X336733D01*
X329108Y358125D01*
X316392D01*
X313822Y355555D01*
X308704D01*
X307567Y356692D01*
G01X428740Y125985D02*
Y127485D01*
G03X428097Y128128I-643J0D01*
G01X426664D01*
G03X425809Y127273I0J-855D01*
G01Y124046D01*
X423284Y121521D01*
X421084D01*
X420966Y121544D01*
X419203Y121897D01*
X417205Y122297D01*
X403858Y131161D01*
X387728Y155358D01*
X381352Y185349D01*
X384797Y202430D01*
X381316Y218810D01*
X383665Y229847D01*
X369483Y297764D01*
X348431Y330185D01*
X345780Y342662D01*
X343445Y346255D01*
X340425Y349275D01*
X336225D01*
X328600Y356900D01*
X316900D01*
X314330Y354330D01*
X308705D01*
X307567Y353192D01*
G01X421653Y136221D02*
Y134721D01*
G02X421010Y134078I-643J0D01*
G01X415106D01*
X410646Y134970D01*
X406754Y137563D01*
X393222Y157858D01*
X387337Y185556D01*
X390724Y202415D01*
X387423Y217952D01*
X389941Y229801D01*
X375053Y299835D01*
X354040Y332198D01*
X349082Y355524D01*
X341995Y366439D01*
X337708Y370725D01*
X332692D01*
X330675Y368708D01*
Y365908D01*
X328592Y363825D01*
X314808D01*
X310478Y368155D01*
X305404D01*
X304267Y369292D01*
G01X421653Y130709D02*
Y132209D01*
G03X421010Y132853I-644J0D01*
G01X414984D01*
X414866Y132876D01*
X410168Y133816D01*
X405871Y136679D01*
X392072Y157373D01*
X386086Y185549D01*
X389473Y202408D01*
X387049Y213815D01*
X386170Y217952D01*
X388688Y229801D01*
X373902Y299358D01*
X352889Y331721D01*
X347931Y355047D01*
X341037Y365663D01*
X337200Y369500D01*
X333200D01*
X331900Y368200D01*
Y365400D01*
X329100Y362600D01*
X314300D01*
X309970Y366930D01*
X305405D01*
X304267Y365792D01*
G01X388338Y643600D02*
X389288Y644550D01*
X392099D01*
X392973Y643676D01*
Y612276D01*
X391686Y610989D01*
Y609975D01*
X391687Y609974D01*
Y582159D01*
X389916Y580388D01*
Y504242D01*
X387538Y501864D01*
Y496710D01*
X384675Y493847D01*
Y474692D01*
X389888Y469479D01*
Y363821D01*
X370075Y344008D01*
Y326332D01*
X400400Y296007D01*
Y174900D01*
X401974Y173326D01*
Y156946D01*
X400924Y155896D01*
G01X388338Y647149D02*
X389712Y645775D01*
X392607D01*
X394198Y644184D01*
Y611768D01*
X392912Y610482D01*
Y581651D01*
X391141Y579880D01*
Y503734D01*
X388763Y501356D01*
Y496202D01*
X385900Y493339D01*
Y475200D01*
X391113Y469987D01*
Y363313D01*
X371300Y343500D01*
Y326840D01*
X401625Y296515D01*
Y175408D01*
X403199Y173834D01*
Y157170D01*
X404473Y155896D01*
G01X788263Y554763D02*
X788616Y555116D01*
G03Y556017I-450J450D01*
G01X787794Y556838D01*
X787722Y556910D01*
G02X786775Y559201I2292J2288D01*
G01Y560285D01*
X785688Y561372D01*
X783850Y562612D01*
X701574Y578610D01*
X649427Y568478D01*
X636321Y559636D01*
X629837Y550024D01*
X620574Y502371D01*
X642701Y387593D01*
X602225Y185215D01*
X602239Y185196D01*
X598870Y168351D01*
X598869D01*
X595701Y152510D01*
X568988Y112447D01*
X564865Y109699D01*
X558756Y108475D01*
X546825D01*
X537970Y117330D01*
Y127273D01*
G02X540050Y129353I2080J0D01*
G01X541483D01*
G03X542126Y129996I0J643D01*
G01Y131496D01*
G01X790737Y557237D02*
X790384Y556884D01*
G02X789483I-451J450D01*
G01X788624Y557741D01*
X788589Y557776D01*
G02X788000Y559200I1424J1423D01*
G01Y560793D01*
X786471Y562322D01*
X784329Y563768D01*
X701807Y579813D01*
X701574Y579858D01*
X648948Y569634D01*
X635438Y560519D01*
X628681Y550503D01*
X619326Y502372D01*
X641452Y387597D01*
X601020Y185441D01*
X601019D01*
X601018Y185436D01*
X600287Y184948D01*
X599948Y183256D01*
X600450Y182503D01*
X600112Y180811D01*
X599359Y180309D01*
X599020Y178618D01*
X599522Y177865D01*
X599184Y176173D01*
X598431Y175671D01*
X598092Y173980D01*
X598594Y173227D01*
X598256Y171535D01*
X597503Y171033D01*
X597164Y169342D01*
X597667Y168589D01*
X594547Y152988D01*
X568104Y113331D01*
X564387Y110853D01*
X561511Y110278D01*
X558634Y109700D01*
X547333D01*
X539195Y117838D01*
Y127273D01*
G02X540050Y128128I855J0D01*
G01X541483D01*
G02X542126Y127485I0J-643D01*
G01Y125985D01*
G01X768263Y552763D02*
X768616Y553116D01*
G03Y554017I-450J450D01*
G01X762987Y559646D01*
X695590Y572743D01*
X651033Y564082D01*
X639902Y556572D01*
X634067Y547921D01*
X625612Y504438D01*
X649225Y385373D01*
X602571Y152110D01*
X574532Y110045D01*
X566402Y104625D01*
X566164Y104577D01*
X562820Y103906D01*
X559357Y103213D01*
X543325D01*
X530884Y115654D01*
Y131970D01*
G02X532992Y134078I2108J0D01*
G01X534396D01*
G03X535039Y134721I0J643D01*
G01Y136221D01*
G01X770737Y555237D02*
X770384Y554884D01*
G02X769483I-450J450D01*
G01X763589Y560778D01*
X695590Y573991D01*
X650554Y565238D01*
X639019Y557455D01*
X632911Y548400D01*
X624363Y504436D01*
X647975Y385374D01*
X605709Y174050D01*
X605004Y173581D01*
X604665Y171889D01*
X605136Y171183D01*
X604798Y169492D01*
X604092Y169021D01*
X603753Y167329D01*
X604224Y166623D01*
X603886Y164932D01*
X603180Y164461D01*
X602841Y162770D01*
X603312Y162064D01*
X602974Y160372D01*
X602268Y159901D01*
X601930Y158210D01*
X602400Y157504D01*
X601417Y152588D01*
X573648Y110929D01*
X565924Y105779D01*
X561743Y104941D01*
X560906Y104773D01*
X559235Y104438D01*
X543833D01*
X532109Y116162D01*
Y131970D01*
G02X532992Y132853I883J0D01*
G01X534395D01*
G02X535039Y132209I0J-644D01*
G01Y130709D01*
G01X728682Y549946D02*
X729035Y550299D01*
G03Y551200I-450J450D01*
G01X728213Y552021D01*
G02X727375Y554048I2027J2025D01*
G01Y554510D01*
G03X727038Y555322I-1149J-1D01*
G01X726565Y555796D01*
X724820Y557541D01*
X719393Y561202D01*
X689689Y566975D01*
X654614Y560156D01*
X644024Y553014D01*
X638034Y544131D01*
X630999Y507929D01*
X655414Y384816D01*
X608814Y151818D01*
X578560Y106435D01*
X569802Y100596D01*
X560380Y98713D01*
X540614D01*
X523797Y115530D01*
Y127273D01*
G02X525877Y129353I2080J0D01*
G01X527310D01*
G03X527953Y129996I0J643D01*
G01Y131496D01*
G01X731156Y552420D02*
X730803Y552067D01*
G02X729903I-450J450D01*
G01X729901Y552069D01*
Y552068D01*
X729490Y552478D01*
X729080Y552888D01*
G02X728600Y554047I1159J1159D01*
G01Y554511D01*
G03X727905Y556189I-2374J0D01*
G01X725603Y558491D01*
X719872Y562358D01*
X689689Y568223D01*
X654135Y561312D01*
X643141Y553897D01*
X636878Y544610D01*
X629750Y507927D01*
X654164Y384817D01*
X612284Y175418D01*
X611578Y174947D01*
X611240Y173255D01*
X611711Y172549D01*
X611372Y170858D01*
X610666Y170387D01*
X610328Y168696D01*
X610799Y167990D01*
X610460Y166298D01*
X609754Y165827D01*
X609416Y164136D01*
X609887Y163430D01*
X609549Y161738D01*
X608843Y161268D01*
X608504Y159576D01*
X608975Y158870D01*
X607660Y152296D01*
X577676Y107319D01*
X569324Y101750D01*
X560258Y99938D01*
X541122D01*
X525022Y116038D01*
Y127273D01*
G02X525877Y128128I855J0D01*
G01X527310D01*
G02X527953Y127485I0J-643D01*
G01Y125985D01*
G01X708682Y551846D02*
X709035Y552199D01*
G03Y553101I-451J451D01*
G01X708214Y553921D01*
G02X707410Y555861I1940J1941D01*
G01Y557372D01*
X706372Y558910D01*
X688971Y562197D01*
X658041Y556181D01*
X647305Y548943D01*
X642872Y542372D01*
X639564Y525555D01*
X636196Y508439D01*
X661413Y382333D01*
X619425Y172406D01*
Y172405D01*
X616116Y155860D01*
X615142Y150986D01*
X582747Y102957D01*
X573373Y96697D01*
X560702Y94164D01*
X538203D01*
X516710Y115657D01*
Y131969D01*
G02X518819Y134078I2109J0D01*
G01X520223D01*
G03X520866Y134721I0J643D01*
G01Y136221D01*
G01X711156Y554320D02*
X710803Y553967D01*
G02X709903I-450J450D01*
G01X709901Y553969D01*
Y553968D01*
X709080Y554788D01*
G02X708635Y555862I1074J1074D01*
G01Y557747D01*
X707102Y560019D01*
X688968Y563445D01*
X657562Y557337D01*
X654672Y555388D01*
X651988Y553579D01*
X646422Y549826D01*
X641717Y542852D01*
X638361Y525792D01*
X636678Y517234D01*
X634947Y508437D01*
X660163Y382333D01*
X618223Y172646D01*
X617517Y172175D01*
X617179Y170484D01*
X617650Y169778D01*
X617311Y168086D01*
X616605Y167616D01*
X616267Y165924D01*
X616738Y165218D01*
X616399Y163527D01*
X615693Y163056D01*
X615355Y161364D01*
X615826Y160658D01*
X615487Y158967D01*
X614781Y158496D01*
X614443Y156805D01*
X614914Y156099D01*
X613988Y151468D01*
X581866Y103842D01*
X572895Y97851D01*
X560580Y95389D01*
X538711D01*
X517935Y116165D01*
Y131969D01*
G02X518819Y132853I884J0D01*
G01X520222D01*
G02X520866Y132209I0J-644D01*
G01Y130709D01*
G01X686198Y552098D02*
X686551Y552451D01*
G03Y553353I-451J451D01*
G01X685730Y554173D01*
G03X683762Y554988I-1968J-1968D01*
G01X679205D01*
X658425Y550972D01*
X652066Y546681D01*
X647339Y539672D01*
X641324Y508734D01*
X641325D01*
X667550Y377581D01*
X625769Y168662D01*
X625770D01*
X622560Y152612D01*
X621648Y148051D01*
X588816Y99380D01*
X576595Y91168D01*
X568816Y89614D01*
X536253D01*
X509624Y116243D01*
Y127274D01*
G02X511703Y129353I2079J0D01*
G01X513136D01*
G03X513779Y129996I0J643D01*
G01Y131496D01*
G01X688672Y554572D02*
X688319Y554219D01*
G02X687419I-450J450D01*
G01X687417Y554221D01*
Y554220D01*
X686596Y555040D01*
G03X683761Y556213I-2833J-2835D01*
G01X679087D01*
X657947Y552128D01*
X651183Y547563D01*
X646183Y540151D01*
X640075Y508731D01*
X666300Y377581D01*
X624666Y169400D01*
X623961Y168930D01*
X623623Y167238D01*
X624093Y166532D01*
X623755Y164841D01*
X623049Y164370D01*
X622711Y162679D01*
X623182Y161973D01*
X622843Y160281D01*
X622137Y159810D01*
X621799Y158119D01*
X622270Y157413D01*
X621931Y155721D01*
X621225Y155251D01*
X620887Y153559D01*
X621358Y152853D01*
X620494Y148533D01*
X587934Y100264D01*
X576115Y92322D01*
X575389Y92177D01*
X572406Y91581D01*
X568694Y90839D01*
X536761D01*
X510849Y116751D01*
Y127274D01*
G02X511703Y128128I854J0D01*
G01X513136D01*
G02X513779Y127485I0J-643D01*
G01Y125985D01*
G01X671024Y544571D02*
X671377Y544924D01*
G03Y545826I-451J451D01*
G01X670556Y546646D01*
G03X668728Y547403I-1828J-1828D01*
G01X664368D01*
X657586Y544609D01*
X652216Y537138D01*
X647021Y510420D01*
X673680Y376289D01*
X631804Y166900D01*
X631805D01*
X628595Y150850D01*
Y150851D01*
X627803Y146888D01*
X593063Y95388D01*
X585608Y90405D01*
X578154Y85422D01*
X571612Y84114D01*
X535348D01*
X502461Y117001D01*
Y131893D01*
G02X504646Y134078I2185J0D01*
G01X506050D01*
G03X506693Y134721I0J643D01*
G01Y136221D01*
G01X673498Y547045D02*
X673145Y546692D01*
G02X672245I-450J450D01*
G01X672243Y546694D01*
Y546693D01*
X671422Y547513D01*
G03X668727Y548628I-2693J-2695D01*
G01X664125D01*
X656795Y545609D01*
X651064Y537636D01*
X645772Y510417D01*
X672430Y376290D01*
X630702Y167638D01*
X629996Y167168D01*
X629658Y165476D01*
X630128Y164770D01*
X629790Y163079D01*
X629084Y162608D01*
X628746Y160916D01*
X629217Y160210D01*
X628878Y158519D01*
X628172Y158048D01*
X627834Y156357D01*
X628305Y155651D01*
X627966Y153959D01*
X627260Y153488D01*
X626922Y151797D01*
X627393Y151091D01*
X626649Y147370D01*
X592182Y96273D01*
X577675Y86576D01*
X571490Y85339D01*
X535856D01*
X503686Y117509D01*
Y131893D01*
G02X504646Y132853I960J0D01*
G01X506049D01*
G02X506693Y132209I0J-644D01*
G01Y130709D01*
G01X825263Y553263D02*
X825616Y553616D01*
G03Y554518I-451J451D01*
G01X824795Y555338D01*
X819929Y560204D01*
X805289Y570002D01*
X706058Y589291D01*
X645658Y577552D01*
X629103Y566387D01*
X621331Y554863D01*
X610245Y497847D01*
X631684Y387566D01*
X589200Y186669D01*
Y186668D01*
X581662Y151022D01*
X560442Y118338D01*
X556610Y117575D01*
X553798D01*
X552143Y119230D01*
Y127273D01*
G02X554223Y129353I2080J0D01*
G01X555656D01*
G03X556299Y129996I0J643D01*
G01Y131496D01*
G01X827737Y555737D02*
X827384Y555384D01*
G02X826483I-450J450D01*
G01X820711Y561156D01*
X805765Y571158D01*
X706058Y590539D01*
X645179Y578708D01*
X628220Y567270D01*
X620175Y555342D01*
X608997Y497847D01*
X630434Y387576D01*
X609217Y287248D01*
X588001Y186922D01*
X587290Y186459D01*
X586933Y184771D01*
X587396Y184060D01*
X587039Y182372D01*
X586328Y181909D01*
X585971Y180222D01*
X586434Y179511D01*
X586077Y177823D01*
X585366Y177360D01*
X585009Y175672D01*
X585472Y174961D01*
X585115Y173273D01*
X584404Y172811D01*
X584047Y171123D01*
X584510Y170412D01*
X580510Y151499D01*
X559695Y119439D01*
X556489Y118800D01*
X554306D01*
X553368Y119738D01*
Y127273D01*
G02X554223Y128128I855J0D01*
G01X555656D01*
G02X556299Y127485I0J-643D01*
G01Y125985D01*
G01X806763Y554763D02*
X807116Y555116D01*
G03Y556017I-450J450D01*
G01X807038Y556094D01*
X807039Y556095D01*
X806632Y556502D01*
G02X805936Y558183I1680J1680D01*
G01Y560925D01*
X805077Y561784D01*
X801760Y563993D01*
X701689Y583544D01*
X657685Y574989D01*
Y574988D01*
X647751Y573058D01*
X633172Y563221D01*
X625476Y551813D01*
X615597Y500952D01*
X637583Y387757D01*
X590376Y163921D01*
X587703Y151246D01*
X564536Y115569D01*
X561704Y113729D01*
X560927Y113573D01*
X559517Y113292D01*
X559274Y113244D01*
X558423Y113075D01*
X550992D01*
X545056Y119011D01*
Y131969D01*
G02X547165Y134078I2109J0D01*
G01X548569D01*
G03X549212Y134721I0J643D01*
G01Y136221D01*
G01X809237Y557237D02*
X808884Y556884D01*
G02X807984I-450J450D01*
G01X807982Y556886D01*
Y556885D01*
X807498Y557369D01*
G02X807161Y558183I814J814D01*
G01Y561433D01*
X805858Y562737D01*
X802236Y565149D01*
X764395Y572542D01*
Y572544D01*
X726797Y579888D01*
X701690Y584793D01*
X701689D01*
Y584792D01*
X656460Y575999D01*
Y575998D01*
X647272Y574214D01*
X632289Y564104D01*
X624320Y552292D01*
X614349Y500952D01*
X636333Y387767D01*
X592659Y180685D01*
X591948Y180221D01*
X591592Y178533D01*
X592055Y177823D01*
X591699Y176135D01*
X590989Y175671D01*
X590633Y173983D01*
X591096Y173273D01*
X590740Y171585D01*
X590029Y171121D01*
X589673Y169434D01*
X590136Y168723D01*
X589780Y167035D01*
X589069Y166572D01*
X588713Y164884D01*
X589177Y164173D01*
X586551Y151722D01*
X563650Y116455D01*
X561233Y114885D01*
X558302Y114300D01*
X551500D01*
X546281Y119519D01*
Y131969D01*
G02X547165Y132853I884J0D01*
G01X548568D01*
G02X549212Y132209I0J-644D01*
G01Y130709D01*
G54D67*
G01X208370Y491570D02*
X207600Y492340D01*
Y495630D01*
G01D02*
X211940D01*
X214040Y497730D01*
G01X352921Y536521D02*
X354098D01*
X355659Y534960D01*
X358730D01*
G01X304124Y570227D02*
X299655D01*
X297292Y572590D01*
Y575349D01*
G01X310092Y577909D02*
X326133D01*
X328173Y579949D01*
G01X297292Y577909D02*
X292123D01*
X291839Y578193D01*
G01X323039Y677049D02*
X326726D01*
X328356Y678679D01*
G01X365230Y529840D02*
Y528796D01*
X365326Y528700D01*
X365327D01*
X367200Y526827D01*
Y526826D01*
X367201Y526825D01*
Y526800D01*
X367500D01*
G01X359439Y540188D02*
X358730Y539479D01*
Y534960D01*
G54D58*
X370950Y563500D03*
X363450Y559625D03*
Y567375D03*
X828266Y350214D03*
X820766Y346339D03*
Y354089D03*
G54D49*
X214040Y504230D03*
X216600D03*
X219160D03*
Y497730D03*
X214040D03*
G54D68*
G01X146750Y584200D02*
X151182D01*
X152640Y582742D01*
G01X164179Y572940D02*
X154650D01*
G01X169625Y575115D02*
X155198D01*
X154150Y576163D01*
Y581232D01*
X152640Y582742D01*
G01X172047Y570867D02*
X171827D01*
X169754Y572940D01*
X167500D01*
G01D02*
X164179D01*
G01X299100Y589200D02*
Y592593D01*
X302147Y595640D01*
X303250D01*
G01X337502Y589593D02*
X336132D01*
X331673Y585134D01*
Y579949D01*
G01X331002Y594713D02*
Y596810D01*
X327538Y600274D01*
G01X296750Y600760D02*
X290627D01*
X288286Y598419D01*
G54D59*
X367620Y603164D03*
Y599564D03*
X361800Y603500D03*
Y599900D03*
G54D69*
G01X712000Y442100D02*
X707900Y438000D01*
X698580D01*
X698275Y438305D01*
G01X811490Y349941D02*
Y355379D01*
X817700Y361589D01*
X830531D01*
G01X811300Y395900D02*
X811184Y395784D01*
Y383716D01*
X830531Y364369D01*
Y361589D01*
G01X820150Y433900D02*
X812950Y441100D01*
X808100D01*
M02*
